FILE_TYPE = MACRO_DRAWING;
SET COLOR_WIRE YELLOW;
SET COLOR_PROP MONO;
SET COLOR_DOT WHITE;
SET COLOR_ARC YELLOW;
SET COLOR_BODY GREEN;
SET COLOR_NOTE MONO;
SET PROP_DISPLAY VALUE;
SET PAGE_NUMBER P228;
FORCEADD PVDDQ_KLM..1
(2525 1700);
FORCEPROP 3 LASTPIN (2525 1650) SIG_NAME PVDDQ_KLM\g
J 0
(2535 1660);
DISPLAY 0.659574 (2535 1660);
PAINT MONO (2535 1660);
DISPLAY INVISIBLE (2535 1660);
FORCEPROP 1 LAST VOLTAGE 1.2V
J 0
(2480 1657);
DISPLAY 0.340426 (2480 1657);
PAINT SKYBLUE (2480 1657);
DISPLAY INVISIBLE (2480 1657);
FORCEPROP 2 LAST CDS_LIB mstr_symbols
J 0
(2525 1700);
PAINT ORANGE (2525 1700);
DISPLAY INVISIBLE (2525 1700);
FORCEPROP 2 LAST ROOM VDDQ_KLM_PWR_VR
J 0
(2775 1800);
PAINT ORANGE (2775 1800);
DISPLAY INVISIBLE (2775 1800);
FORCEPROP 1 LAST PATH I109
J 0
(2575 1725);
DISPLAY 0.872340 (2575 1725);
PAINT AQUA (2575 1725);
DISPLAY INVISIBLE (2575 1725);
FORCEPROP 2 LAST BOM_COST MEM_VRD_PVDDQ_CD
J 0
(2600 1800);
PAINT MONO (2600 1800);
DISPLAY INVISIBLE (2600 1800);
FORCEPROP 1 LAST BODY_TYPE PLUMBING
J 0
(2480 1657);
DISPLAY 0.340426 (2480 1657);
PAINT GREEN (2480 1657);
DISPLAY INVISIBLE (2480 1657);
FORCEPROP 1 LAST HDL_POWER PVDDQ_KLM
J 1
(2525 1750);
DISPLAY 0.872340 (2525 1750);
PAINT GREEN (2525 1750);
DISPLAY INVISIBLE (2525 1750);
FORCEADD CAP..1
(2400 2825);
FORCEPROP 1 LASTPIN (2400 2725) $PN 2
J 0
(2410 2705);
DISPLAY 0.617021 (2410 2705);
PAINT ORANGE (2410 2705);
FORCEPROP 1 LAST MATERIAL X5R
J 0
(2450 2725);
DISPLAY 0.617021 (2450 2725);
PAINT SKYBLUE (2450 2725);
FORCEPROP 1 LAST TOLERANCE 20%
J 0
(2450 2775);
DISPLAY 0.617021 (2450 2775);
PAINT SKYBLUE (2450 2775);
FORCEPROP 1 LASTPIN (2400 2925) $PN 1
J 0
(2410 2905);
DISPLAY 0.617021 (2410 2905);
PAINT ORANGE (2410 2905);
FORCEPROP 1 LAST VOLTAGE 4V
J 0
(2450 2825);
DISPLAY 0.617021 (2450 2825);
PAINT SKYBLUE (2450 2825);
FORCEPROP 1 LAST LOCATION C8L1
J 0
(2450 2925);
DISPLAY 0.617021 (2450 2925);
PAINT AQUA (2450 2925);
FORCEPROP 1 LAST PART_NUMBER 602433-112
J 0
(2450 2675);
DISPLAY 0.617021 (2450 2675);
PAINT BLUE (2450 2675);
FORCEPROP 1 LAST VALUE 100UF
J 0
(2450 2875);
DISPLAY 0.617021 (2450 2875);
PAINT SKYBLUE (2450 2875);
FORCEPROP 1 LAST PACK_TYPE 0805
J 0
(2450 2625);
DISPLAY 0.617021 (2450 2625);
PAINT SKYBLUE (2450 2625);
FORCEPROP 2 LAST CDS_LIB mstr_discrete
J 0
(2400 2825);
PAINT MONO (2400 2825);
DISPLAY INVISIBLE (2400 2825);
FORCEPROP 2 LAST CDS_LOCATION C8L1
J 0
(2450 2925);
DISPLAY 0.617021 (2450 2925);
PAINT AQUA (2450 2925);
DISPLAY INVISIBLE (2450 2925);
FORCEPROP 1 LAST PATH I110
J 0
(2450 2975);
DISPLAY 0.978723 (2450 2975);
PAINT WHITE (2450 2975);
DISPLAY INVISIBLE (2450 2975);
FORCEPROP 2 LAST SEC 1
J 0
(2450 3025);
DISPLAY 0.680851 (2450 3025);
PAINT MONO (2450 3025);
DISPLAY INVISIBLE (2450 3025);
FORCEPROP 2 LAST SEC_TYPE 0805
J 0
(2450 3025);
DISPLAY 1.021277 (2450 3025);
PAINT ORANGE (2450 3025);
DISPLAY INVISIBLE (2450 3025);
FORCEPROP 2 LAST BOM_COST MEM_VRD_PVDDQ_CD
J 0
(2450 2975);
PAINT MONO (2450 2975);
DISPLAY INVISIBLE (2450 2975);
FORCEPROP 2 LAST ROOM VDDQ_KLM_PWR_VR
J 0
(2450 2975);
PAINT MONO (2450 2975);
DISPLAY INVISIBLE (2450 2975);
FORCEADD GND..1
(4250 1050);
FORCEPROP 3 LASTPIN (4250 1100) SIG_NAME GND\g
J 0
(4260 1110);
DISPLAY 0.659574 (4260 1110);
PAINT MONO (4260 1110);
DISPLAY INVISIBLE (4260 1110);
FORCEPROP 2 LAST ROOM VDDQ_KLM_PWR_VR
J 0
(3700 1125);
PAINT ORANGE (3700 1125);
DISPLAY INVISIBLE (3700 1125);
FORCEPROP 2 LAST BOM_COST MEM_VRD_PVDDQ_CD
J 0
(3925 1125);
PAINT MONO (3925 1125);
DISPLAY INVISIBLE (3925 1125);
FORCEPROP 1 LAST SIZE 1B
J 0
(4325 1000);
DISPLAY 0.893617 (4325 1000);
PAINT GREEN (4325 1000);
DISPLAY INVISIBLE (4325 1000);
FORCEPROP 1 LAST PATH I114
J 0
(4325 1050);
DISPLAY 1.170213 (4325 1050);
PAINT AQUA (4325 1050);
DISPLAY INVISIBLE (4325 1050);
FORCEPROP 2 LAST CDS_LIB mstr_symbols
J 0
(4250 1050);
PAINT ORANGE (4250 1050);
DISPLAY INVISIBLE (4250 1050);
FORCEPROP 1 LAST VOLTAGE 0
J 0
(4250 1050);
PAINT SKYBLUE (4250 1050);
DISPLAY INVISIBLE (4250 1050);
FORCEPROP 1 LAST BODY_TYPE PLUMBING
J 0
(4205 1007);
DISPLAY 0.340426 (4205 1007);
PAINT GREEN (4205 1007);
DISPLAY INVISIBLE (4205 1007);
FORCEPROP 1 LAST HDL_POWER GND
J 0
(4250 1200);
DISPLAY 0.893617 (4250 1200);
PAINT GREEN (4250 1200);
DISPLAY INVISIBLE (4250 1200);
FORCEADD VCC_CORE..1
(-675 1350);
FORCEPROP 3 LASTPIN (-675 1300) SIG_NAME VR_FET_SW_P12V_STBY_PVDDQ_KLM\g
J 0
(-665 1310);
DISPLAY 0.659574 (-665 1310);
PAINT MONO (-665 1310);
DISPLAY INVISIBLE (-665 1310);
FORCEPROP 1 LAST HDL_POWER VR_FET_SW_P12V_STBY_PVDDQ_KLM
J 1
(-675 1400);
DISPLAY 0.617021 (-675 1400);
PAINT GREEN (-675 1400);
FORCEPROP 2 LAST CDS_LIB mstr_symbols
J 0
(-675 1350);
PAINT ORANGE (-675 1350);
DISPLAY INVISIBLE (-675 1350);
FORCEPROP 1 LAST PATH I120
J 0
(-625 1375);
DISPLAY 1.170213 (-625 1375);
PAINT AQUA (-625 1375);
DISPLAY INVISIBLE (-625 1375);
FORCEADD GND..1
(-675 675);
FORCEPROP 3 LASTPIN (-675 725) SIG_NAME GND\g
J 0
(-665 735);
DISPLAY 0.659574 (-665 735);
PAINT MONO (-665 735);
DISPLAY INVISIBLE (-665 735);
FORCEPROP 2 LAST ROOM VDDQ_KLM_PWR_VR
J 0
(-1225 750);
PAINT ORANGE (-1225 750);
DISPLAY INVISIBLE (-1225 750);
FORCEPROP 2 LAST BOM_COST MEM_VRD_PVDDQ_CD
J 0
(-1000 750);
PAINT MONO (-1000 750);
DISPLAY INVISIBLE (-1000 750);
FORCEPROP 1 LAST VOLTAGE 0
J 0
(-675 675);
PAINT SKYBLUE (-675 675);
DISPLAY INVISIBLE (-675 675);
FORCEPROP 1 LAST SIZE 1B
J 0
(-600 625);
DISPLAY 0.893617 (-600 625);
PAINT GREEN (-600 625);
DISPLAY INVISIBLE (-600 625);
FORCEPROP 2 LAST CDS_LIB mstr_symbols
J 0
(-675 675);
PAINT ORANGE (-675 675);
DISPLAY INVISIBLE (-675 675);
FORCEPROP 1 LAST PATH I123
J 0
(-600 675);
DISPLAY 1.170213 (-600 675);
PAINT AQUA (-600 675);
DISPLAY INVISIBLE (-600 675);
FORCEPROP 1 LAST BODY_TYPE PLUMBING
J 0
(-720 632);
DISPLAY 0.340426 (-720 632);
PAINT GREEN (-720 632);
DISPLAY INVISIBLE (-720 632);
FORCEPROP 1 LAST HDL_POWER GND
J 0
(-675 825);
DISPLAY 0.893617 (-675 825);
PAINT GREEN (-675 825);
DISPLAY INVISIBLE (-675 825);
FORCEADD INDUCTOR..1
(-1100 1100);
FORCEPROP 1 LAST VALUE 100NH
J 2
(-1105 1015);
DISPLAY 0.617021 (-1105 1015);
PAINT SKYBLUE (-1105 1015);
FORCEPROP 1 LASTPIN (-1200 1100) $PN 1
J 0
(-1200 1110);
DISPLAY 0.617021 (-1200 1110);
PAINT WHITE (-1200 1110);
FORCEPROP 1 LAST LOCATION L1B1
J 0
(-1200 1150);
DISPLAY 0.617021 (-1200 1150);
PAINT AQUA (-1200 1150);
FORCEPROP 1 LAST PART_NUMBER D92183-020
J 0
(-1200 1200);
DISPLAY 0.617021 (-1200 1200);
PAINT BLUE (-1200 1200);
FORCEPROP 1 LAST MATERIAL IND
J 0
(-1085 1015);
DISPLAY 0.617021 (-1085 1015);
PAINT SKYBLUE (-1085 1015);
FORCEPROP 1 LAST PACK_TYPE SM
J 0
(-810 1015);
DISPLAY 0.617021 (-810 1015);
PAINT SKYBLUE (-810 1015);
FORCEPROP 1 LASTPIN (-1000 1100) $PN 2
J 2
(-990 1110);
DISPLAY 0.617021 (-990 1110);
PAINT WHITE (-990 1110);
FORCEPROP 2 LAST CDS_LOCATION L1B1
J 0
(-1200 1150);
DISPLAY 0.617021 (-1200 1150);
PAINT AQUA (-1200 1150);
DISPLAY INVISIBLE (-1200 1150);
FORCEPROP 2 LAST CDS_LIB mstr_discrete
J 0
(-1100 1100);
PAINT ORANGE (-1100 1100);
DISPLAY INVISIBLE (-1100 1100);
FORCEPROP 2 LAST BOM_COST MEM_VRD_PVDDQ_CD
J 0
(-1200 1250);
PAINT MONO (-1200 1250);
DISPLAY INVISIBLE (-1200 1250);
FORCEPROP 1 LAST PATH I124
J 0
(-1200 1250);
DISPLAY 1.319149 (-1200 1250);
PAINT ORANGE (-1200 1250);
DISPLAY INVISIBLE (-1200 1250);
FORCEPROP 2 LAST ROOM VDDQ_KLM_PWR_VR
J 0
(-1200 1250);
PAINT MONO (-1200 1250);
DISPLAY INVISIBLE (-1200 1250);
FORCEPROP 2 LAST SEC_TYPE SM
J 0
(-1195 1320);
DISPLAY 1.021277 (-1195 1320);
PAINT ORANGE (-1195 1320);
DISPLAY INVISIBLE (-1195 1320);
FORCEPROP 2 LAST SEC 1
J 0
(-1195 1320);
DISPLAY 0.680851 (-1195 1320);
PAINT MONO (-1195 1320);
DISPLAY INVISIBLE (-1195 1320);
FORCEADD CAPP..1
(-675 900);
FORCEPROP 1 LASTPIN (-675 800) $PN 2
J 0
(-665 785);
DISPLAY 0.617021 (-665 785);
PAINT ORANGE (-665 785);
FORCEPROP 1 LASTPIN (-675 1000) $PN 1
J 0
(-665 985);
DISPLAY 0.617021 (-665 985);
PAINT ORANGE (-665 985);
FORCEPROP 1 LAST TOLERANCE 20%
J 0
(-625 900);
DISPLAY 0.617021 (-625 900);
PAINT SKYBLUE (-625 900);
FORCEPROP 1 LAST VOLTAGE 16V
J 0
(-625 850);
DISPLAY 0.617021 (-625 850);
PAINT SKYBLUE (-625 850);
FORCEPROP 1 LAST PART_NUMBER A31228-047
J 0
(-625 700);
DISPLAY 0.617021 (-625 700);
PAINT BLUE (-625 700);
FORCEPROP 1 LAST VALUE 270UF
J 0
(-625 950);
DISPLAY 0.617021 (-625 950);
PAINT SKYBLUE (-625 950);
FORCEPROP 1 LAST PACK_TYPE 2626
J 0
(-625 750);
DISPLAY 0.617021 (-625 750);
PAINT SKYBLUE (-625 750);
FORCEPROP 1 LAST MATERIAL OSCON
J 0
(-625 800);
DISPLAY 0.617021 (-625 800);
PAINT SKYBLUE (-625 800);
FORCEPROP 1 LAST LOCATION C1B10
J 0
(-625 1000);
DISPLAY 0.617021 (-625 1000);
PAINT AQUA (-625 1000);
FORCEPROP 2 LAST CDS_LIB mstr_discrete
J 0
(-675 900);
PAINT ORANGE (-675 900);
DISPLAY INVISIBLE (-675 900);
FORCEPROP 2 LAST CDS_LOCATION C1B10
J 0
(-625 1000);
DISPLAY 0.617021 (-625 1000);
PAINT AQUA (-625 1000);
DISPLAY INVISIBLE (-625 1000);
FORCEPROP 2 LAST ROOM VDDQ_KLM_PWR_VR
J 0
(-625 1050);
DISPLAY 1.361702 (-625 1050);
PAINT ORANGE (-625 1050);
DISPLAY INVISIBLE (-625 1050);
FORCEPROP 1 LAST PATH I175
J 0
(-625 1050);
DISPLAY 1.319149 (-625 1050);
PAINT ORANGE (-625 1050);
DISPLAY INVISIBLE (-625 1050);
FORCEPROP 2 LAST SEC 1
J 0
(-625 1125);
DISPLAY 0.680851 (-625 1125);
PAINT MONO (-625 1125);
DISPLAY INVISIBLE (-625 1125);
FORCEPROP 2 LAST SEC_TYPE 2626
J 0
(-625 1125);
DISPLAY 1.021277 (-625 1125);
PAINT ORANGE (-625 1125);
DISPLAY INVISIBLE (-625 1125);
FORCEADD P12V_STBY..1
(-1400 1375);
FORCEPROP 3 LASTPIN (-1400 1325) SIG_NAME P12V_STBY\g
J 0
(-1390 1335);
DISPLAY 0.659574 (-1390 1335);
PAINT MONO (-1390 1335);
DISPLAY INVISIBLE (-1390 1335);
FORCEPROP 1 LAST VOLTAGE 12.0V
J 0
(-1445 1332);
DISPLAY 0.340426 (-1445 1332);
PAINT SKYBLUE (-1445 1332);
DISPLAY INVISIBLE (-1445 1332);
FORCEPROP 2 LAST CDS_LIB mstr_symbols
J 0
(-1400 1375);
PAINT ORANGE (-1400 1375);
DISPLAY INVISIBLE (-1400 1375);
FORCEPROP 1 LAST SIZE 1B
J 0
(-1355 1397);
DISPLAY 0.340426 (-1355 1397);
PAINT GREEN (-1355 1397);
DISPLAY INVISIBLE (-1355 1397);
FORCEPROP 1 LAST PATH I182
J 0
(-1355 1377);
DISPLAY 0.340426 (-1355 1377);
PAINT GREEN (-1355 1377);
DISPLAY INVISIBLE (-1355 1377);
FORCEPROP 1 LAST BODY_TYPE PLUMBING
J 0
(-1445 1332);
DISPLAY 0.340426 (-1445 1332);
PAINT GREEN (-1445 1332);
DISPLAY INVISIBLE (-1445 1332);
FORCEPROP 1 LAST HDL_POWER P12V_STBY
J 0
(-1700 1250);
DISPLAY 0.872340 (-1700 1250);
PAINT ORANGE (-1700 1250);
DISPLAY INVISIBLE (-1700 1250);
FORCEADD CAP..1
(-2300 2900);
FORCEPROP 1 LASTPIN (-2300 2800) $PN 2
J 0
(-2290 2780);
DISPLAY 0.617021 (-2290 2780);
PAINT ORANGE (-2290 2780);
FORCEPROP 1 LAST PACK_TYPE 0805LF
J 0
(-2250 2700);
DISPLAY 0.617021 (-2250 2700);
PAINT SKYBLUE (-2250 2700);
FORCEPROP 1 LAST MATERIAL X6S
J 0
(-2250 2800);
DISPLAY 0.617021 (-2250 2800);
PAINT SKYBLUE (-2250 2800);
FORCEPROP 1 LASTPIN (-2300 3000) $PN 1
J 0
(-2290 2980);
DISPLAY 0.617021 (-2290 2980);
PAINT ORANGE (-2290 2980);
FORCEPROP 1 LAST TOLERANCE 20%
J 0
(-2250 2850);
DISPLAY 0.617021 (-2250 2850);
PAINT SKYBLUE (-2250 2850);
FORCEPROP 1 LAST PART_NUMBER C95333-002
J 0
(-2250 2750);
DISPLAY 0.617021 (-2250 2750);
PAINT BLUE (-2250 2750);
FORCEPROP 1 LAST VALUE 22UF
J 0
(-2250 2950);
DISPLAY 0.617021 (-2250 2950);
PAINT SKYBLUE (-2250 2950);
FORCEPROP 1 LAST LOCATION C8P2
J 0
(-2250 3000);
DISPLAY 0.617021 (-2250 3000);
PAINT AQUA (-2250 3000);
FORCEPROP 2 LAST CDS_LOCATION C8P2
J 0
(-2250 3000);
DISPLAY 0.617021 (-2250 3000);
PAINT AQUA (-2250 3000);
DISPLAY INVISIBLE (-2250 3000);
FORCEPROP 2 LAST CDS_LIB mstr_discrete
J 0
(-2300 2900);
PAINT ORANGE (-2300 2900);
DISPLAY INVISIBLE (-2300 2900);
FORCEPROP 1 LAST VOLTAGE 4V
J 0
(-2250 2900);
PAINT SKYBLUE (-2250 2900);
DISPLAY INVISIBLE (-2250 2900);
FORCEPROP 2 LAST BOM_COST MEM_VRD_PVDDQ_KLM
J 0
(-2250 3050);
PAINT MONO (-2250 3050);
DISPLAY INVISIBLE (-2250 3050);
FORCEPROP 1 LAST PATH I183
J 0
(-2250 3050);
DISPLAY 0.978723 (-2250 3050);
PAINT WHITE (-2250 3050);
DISPLAY INVISIBLE (-2250 3050);
FORCEPROP 2 LAST ROOM VDDQ_KLM_CPU1
J 0
(-2250 3050);
PAINT MONO (-2250 3050);
DISPLAY INVISIBLE (-2250 3050);
FORCEPROP 2 LAST SEC 1
J 0
(-2250 3100);
DISPLAY 0.680851 (-2250 3100);
PAINT MONO (-2250 3100);
DISPLAY INVISIBLE (-2250 3100);
FORCEPROP 2 LAST SEC_TYPE 0805LF
J 0
(-2250 3100);
DISPLAY 1.021277 (-2250 3100);
PAINT ORANGE (-2250 3100);
DISPLAY INVISIBLE (-2250 3100);
FORCEADD CAP..1
(-1900 2900);
FORCEPROP 1 LASTPIN (-1900 2800) $PN 2
J 0
(-1890 2780);
DISPLAY 0.617021 (-1890 2780);
PAINT ORANGE (-1890 2780);
FORCEPROP 1 LASTPIN (-1900 3000) $PN 1
J 0
(-1890 2980);
DISPLAY 0.617021 (-1890 2980);
PAINT ORANGE (-1890 2980);
FORCEPROP 1 LAST LOCATION C8P1
J 0
(-1850 3000);
DISPLAY 0.617021 (-1850 3000);
PAINT AQUA (-1850 3000);
FORCEPROP 1 LAST VALUE 22UF
J 0
(-1850 2950);
DISPLAY 0.617021 (-1850 2950);
PAINT SKYBLUE (-1850 2950);
FORCEPROP 1 LAST TOLERANCE 20%
J 0
(-1850 2850);
DISPLAY 0.617021 (-1850 2850);
PAINT SKYBLUE (-1850 2850);
FORCEPROP 1 LAST PACK_TYPE 0805LF
J 0
(-1850 2700);
DISPLAY 0.617021 (-1850 2700);
PAINT SKYBLUE (-1850 2700);
FORCEPROP 1 LAST MATERIAL X6S
J 0
(-1850 2800);
DISPLAY 0.617021 (-1850 2800);
PAINT SKYBLUE (-1850 2800);
FORCEPROP 1 LAST PART_NUMBER C95333-002
J 0
(-1850 2750);
DISPLAY 0.617021 (-1850 2750);
PAINT BLUE (-1850 2750);
FORCEPROP 2 LAST CDS_LOCATION C8P1
J 0
(-1850 3000);
DISPLAY 0.617021 (-1850 3000);
PAINT AQUA (-1850 3000);
DISPLAY INVISIBLE (-1850 3000);
FORCEPROP 2 LAST CDS_LIB mstr_discrete
J 0
(-1900 2900);
PAINT ORANGE (-1900 2900);
DISPLAY INVISIBLE (-1900 2900);
FORCEPROP 1 LAST VOLTAGE 4V
J 0
(-1850 2900);
PAINT SKYBLUE (-1850 2900);
DISPLAY INVISIBLE (-1850 2900);
FORCEPROP 2 LAST BOM_COST MEM_VRD_PVDDQ_KLM
J 0
(-1850 3050);
PAINT MONO (-1850 3050);
DISPLAY INVISIBLE (-1850 3050);
FORCEPROP 1 LAST PATH I185
J 0
(-1850 3050);
DISPLAY 0.978723 (-1850 3050);
PAINT WHITE (-1850 3050);
DISPLAY INVISIBLE (-1850 3050);
FORCEPROP 2 LAST ROOM VDDQ_KLM_CPU1
J 0
(-1850 3050);
PAINT MONO (-1850 3050);
DISPLAY INVISIBLE (-1850 3050);
FORCEPROP 2 LAST SEC_TYPE 0805LF
J 0
(-1850 3100);
DISPLAY 1.021277 (-1850 3100);
PAINT ORANGE (-1850 3100);
DISPLAY INVISIBLE (-1850 3100);
FORCEPROP 2 LAST SEC 1
J 0
(-1850 3100);
DISPLAY 0.680851 (-1850 3100);
PAINT MONO (-1850 3100);
DISPLAY INVISIBLE (-1850 3100);
FORCEADD CAP..1
(-1550 2900);
FORCEPROP 1 LASTPIN (-1550 2800) $PN 2
J 0
(-1540 2780);
DISPLAY 0.617021 (-1540 2780);
PAINT ORANGE (-1540 2780);
FORCEPROP 1 LASTPIN (-1550 3000) $PN 1
J 0
(-1540 2980);
DISPLAY 0.617021 (-1540 2980);
PAINT ORANGE (-1540 2980);
FORCEPROP 1 LAST LOCATION C2D7
J 0
(-1500 3000);
DISPLAY 0.617021 (-1500 3000);
PAINT AQUA (-1500 3000);
FORCEPROP 1 LAST VALUE 10UF
J 0
(-1500 2950);
DISPLAY 0.617021 (-1500 2950);
PAINT SKYBLUE (-1500 2950);
FORCEPROP 1 LAST TOLERANCE 20%
J 0
(-1500 2850);
DISPLAY 0.617021 (-1500 2850);
PAINT SKYBLUE (-1500 2850);
FORCEPROP 1 LAST PACK_TYPE 0603LF
J 0
(-1500 2700);
DISPLAY 0.617021 (-1500 2700);
PAINT SKYBLUE (-1500 2700);
FORCEPROP 1 LAST VOLTAGE 4V
J 0
(-1500 2900);
DISPLAY 0.617021 (-1500 2900);
PAINT SKYBLUE (-1500 2900);
FORCEPROP 1 LAST MATERIAL X6S
J 0
(-1500 2800);
DISPLAY 0.617021 (-1500 2800);
PAINT SKYBLUE (-1500 2800);
FORCEPROP 1 LAST PART_NUMBER E15431-001
J 0
(-1500 2750);
DISPLAY 0.617021 (-1500 2750);
PAINT BLUE (-1500 2750);
FORCEPROP 2 LAST CDS_LIB mstr_discrete
J 0
(-1550 2900);
PAINT ORANGE (-1550 2900);
DISPLAY INVISIBLE (-1550 2900);
FORCEPROP 2 LAST CDS_LOCATION C2D7
J 0
(-1500 3000);
DISPLAY 0.617021 (-1500 3000);
PAINT AQUA (-1500 3000);
DISPLAY INVISIBLE (-1500 3000);
FORCEPROP 2 LAST BOM_COST MEM_VRD_PVDDQ_KLM
J 0
(-1500 3050);
PAINT MONO (-1500 3050);
DISPLAY INVISIBLE (-1500 3050);
FORCEPROP 1 LAST PATH I186
J 0
(-1500 3050);
DISPLAY 0.978723 (-1500 3050);
PAINT WHITE (-1500 3050);
DISPLAY INVISIBLE (-1500 3050);
FORCEPROP 2 LAST ROOM VDDQ_KLM_CPU1
J 0
(-1500 3050);
PAINT MONO (-1500 3050);
DISPLAY INVISIBLE (-1500 3050);
FORCEPROP 2 LAST SEC_TYPE 0603LF
J 0
(-1500 3100);
DISPLAY 1.021277 (-1500 3100);
PAINT ORANGE (-1500 3100);
DISPLAY INVISIBLE (-1500 3100);
FORCEPROP 2 LAST SEC 1
J 0
(-1500 3100);
DISPLAY 0.680851 (-1500 3100);
PAINT MONO (-1500 3100);
DISPLAY INVISIBLE (-1500 3100);
FORCEADD CAP..1
(-1200 2900);
FORCEPROP 1 LASTPIN (-1200 2800) $PN 2
J 0
(-1190 2780);
DISPLAY 0.617021 (-1190 2780);
PAINT ORANGE (-1190 2780);
FORCEPROP 1 LAST MATERIAL X6S
J 0
(-1150 2800);
DISPLAY 0.617021 (-1150 2800);
PAINT SKYBLUE (-1150 2800);
FORCEPROP 1 LASTPIN (-1200 3000) $PN 1
J 0
(-1190 2980);
DISPLAY 0.617021 (-1190 2980);
PAINT ORANGE (-1190 2980);
FORCEPROP 1 LAST VOLTAGE 4V
J 0
(-1150 2900);
DISPLAY 0.617021 (-1150 2900);
PAINT SKYBLUE (-1150 2900);
FORCEPROP 1 LAST TOLERANCE 20%
J 0
(-1150 2850);
DISPLAY 0.617021 (-1150 2850);
PAINT SKYBLUE (-1150 2850);
FORCEPROP 1 LAST VALUE 10UF
J 0
(-1150 2950);
DISPLAY 0.617021 (-1150 2950);
PAINT SKYBLUE (-1150 2950);
FORCEPROP 1 LAST LOCATION C2D4
J 0
(-1150 3000);
DISPLAY 0.617021 (-1150 3000);
PAINT AQUA (-1150 3000);
FORCEPROP 1 LAST PART_NUMBER E15431-001
J 0
(-1150 2750);
DISPLAY 0.617021 (-1150 2750);
PAINT BLUE (-1150 2750);
FORCEPROP 1 LAST PACK_TYPE 0603LF
J 0
(-1150 2700);
DISPLAY 0.617021 (-1150 2700);
PAINT SKYBLUE (-1150 2700);
FORCEPROP 2 LAST CDS_LIB mstr_discrete
J 0
(-1200 2900);
PAINT ORANGE (-1200 2900);
DISPLAY INVISIBLE (-1200 2900);
FORCEPROP 2 LAST CDS_LOCATION C2D4
J 0
(-1150 3000);
DISPLAY 0.617021 (-1150 3000);
PAINT AQUA (-1150 3000);
DISPLAY INVISIBLE (-1150 3000);
FORCEPROP 2 LAST BOM_COST MEM_VRD_PVDDQ_KLM
J 0
(-1150 3050);
PAINT MONO (-1150 3050);
DISPLAY INVISIBLE (-1150 3050);
FORCEPROP 1 LAST PATH I187
J 0
(-1150 3050);
DISPLAY 0.978723 (-1150 3050);
PAINT WHITE (-1150 3050);
DISPLAY INVISIBLE (-1150 3050);
FORCEPROP 2 LAST ROOM VDDQ_KLM_CPU1
J 0
(-1150 3050);
PAINT MONO (-1150 3050);
DISPLAY INVISIBLE (-1150 3050);
FORCEPROP 2 LAST SEC_TYPE 0603LF
J 0
(-1150 3100);
DISPLAY 1.021277 (-1150 3100);
PAINT ORANGE (-1150 3100);
DISPLAY INVISIBLE (-1150 3100);
FORCEPROP 2 LAST SEC 1
J 0
(-1150 3100);
DISPLAY 0.680851 (-1150 3100);
PAINT MONO (-1150 3100);
DISPLAY INVISIBLE (-1150 3100);
FORCEADD CAP..1
(-850 2900);
FORCEPROP 1 LASTPIN (-850 2800) $PN 2
J 0
(-840 2780);
DISPLAY 0.617021 (-840 2780);
PAINT ORANGE (-840 2780);
FORCEPROP 1 LASTPIN (-850 3000) $PN 1
J 0
(-840 2980);
DISPLAY 0.617021 (-840 2980);
PAINT ORANGE (-840 2980);
FORCEPROP 1 LAST LOCATION C2D5
J 0
(-800 3000);
DISPLAY 0.617021 (-800 3000);
PAINT AQUA (-800 3000);
FORCEPROP 1 LAST VALUE 10UF
J 0
(-800 2950);
DISPLAY 0.617021 (-800 2950);
PAINT SKYBLUE (-800 2950);
FORCEPROP 1 LAST TOLERANCE 20%
J 0
(-800 2850);
DISPLAY 0.617021 (-800 2850);
PAINT SKYBLUE (-800 2850);
FORCEPROP 1 LAST PACK_TYPE 0603LF
J 0
(-800 2700);
DISPLAY 0.617021 (-800 2700);
PAINT SKYBLUE (-800 2700);
FORCEPROP 1 LAST VOLTAGE 4V
J 0
(-800 2900);
DISPLAY 0.617021 (-800 2900);
PAINT SKYBLUE (-800 2900);
FORCEPROP 1 LAST MATERIAL X6S
J 0
(-800 2800);
DISPLAY 0.617021 (-800 2800);
PAINT SKYBLUE (-800 2800);
FORCEPROP 1 LAST PART_NUMBER E15431-001
J 0
(-800 2750);
DISPLAY 0.617021 (-800 2750);
PAINT BLUE (-800 2750);
FORCEPROP 2 LAST CDS_LOCATION C2D5
J 0
(-800 3000);
DISPLAY 0.617021 (-800 3000);
PAINT AQUA (-800 3000);
DISPLAY INVISIBLE (-800 3000);
FORCEPROP 2 LAST CDS_LIB mstr_discrete
J 0
(-850 2900);
PAINT ORANGE (-850 2900);
DISPLAY INVISIBLE (-850 2900);
FORCEPROP 2 LAST BOM_COST MEM_VRD_PVDDQ_KLM
J 0
(-800 3050);
PAINT MONO (-800 3050);
DISPLAY INVISIBLE (-800 3050);
FORCEPROP 1 LAST PATH I188
J 0
(-800 3050);
DISPLAY 0.978723 (-800 3050);
PAINT WHITE (-800 3050);
DISPLAY INVISIBLE (-800 3050);
FORCEPROP 2 LAST ROOM VDDQ_KLM_CPU1
J 0
(-800 3050);
PAINT MONO (-800 3050);
DISPLAY INVISIBLE (-800 3050);
FORCEPROP 2 LAST SEC_TYPE 0603LF
J 0
(-800 3100);
DISPLAY 1.021277 (-800 3100);
PAINT ORANGE (-800 3100);
DISPLAY INVISIBLE (-800 3100);
FORCEPROP 2 LAST SEC 1
J 0
(-800 3100);
DISPLAY 0.680851 (-800 3100);
PAINT MONO (-800 3100);
DISPLAY INVISIBLE (-800 3100);
FORCEADD GND..1
(-500 2525);
FORCEPROP 3 LASTPIN (-500 2575) SIG_NAME GND\g
J 0
(-490 2585);
DISPLAY 0.659574 (-490 2585);
PAINT MONO (-490 2585);
DISPLAY INVISIBLE (-490 2585);
FORCEPROP 2 LAST ROOM VDDQ_ABC_PWR_VR
J 0
(-1050 2600);
PAINT ORANGE (-1050 2600);
DISPLAY INVISIBLE (-1050 2600);
FORCEPROP 2 LAST BOM_COST MEM_VRD_PVDDQ_CD
J 0
(-825 2600);
PAINT MONO (-825 2600);
DISPLAY INVISIBLE (-825 2600);
FORCEPROP 1 LAST SIZE 1B
J 0
(-425 2475);
DISPLAY 0.893617 (-425 2475);
PAINT GREEN (-425 2475);
DISPLAY INVISIBLE (-425 2475);
FORCEPROP 1 LAST VOLTAGE 0
J 0
(-500 2525);
PAINT SKYBLUE (-500 2525);
DISPLAY INVISIBLE (-500 2525);
FORCEPROP 2 LAST CDS_LIB mstr_symbols
J 0
(-500 2525);
PAINT ORANGE (-500 2525);
DISPLAY INVISIBLE (-500 2525);
FORCEPROP 1 LAST PATH I189
J 0
(-425 2525);
DISPLAY 0.872340 (-425 2525);
PAINT AQUA (-425 2525);
DISPLAY INVISIBLE (-425 2525);
FORCEPROP 1 LAST BODY_TYPE PLUMBING
J 0
(-545 2482);
DISPLAY 0.340426 (-545 2482);
PAINT GREEN (-545 2482);
DISPLAY INVISIBLE (-545 2482);
FORCEPROP 1 LAST HDL_POWER GND
J 0
(-500 2675);
DISPLAY 0.893617 (-500 2675);
PAINT GREEN (-500 2675);
DISPLAY INVISIBLE (-500 2675);
FORCEADD CAP..1
(-500 2900);
FORCEPROP 1 LAST PACK_TYPE 0603LF
J 0
(-450 2700);
DISPLAY 0.617021 (-450 2700);
PAINT SKYBLUE (-450 2700);
FORCEPROP 1 LASTPIN (-500 2800) $PN 2
J 0
(-490 2780);
DISPLAY 0.617021 (-490 2780);
PAINT ORANGE (-490 2780);
FORCEPROP 1 LAST MATERIAL X6S
J 0
(-450 2800);
DISPLAY 0.617021 (-450 2800);
PAINT SKYBLUE (-450 2800);
FORCEPROP 1 LAST LOCATION C2D6
J 0
(-450 3000);
DISPLAY 0.617021 (-450 3000);
PAINT AQUA (-450 3000);
FORCEPROP 1 LAST VALUE 10UF
J 0
(-450 2950);
DISPLAY 0.617021 (-450 2950);
PAINT SKYBLUE (-450 2950);
FORCEPROP 1 LAST TOLERANCE 20%
J 0
(-450 2850);
DISPLAY 0.617021 (-450 2850);
PAINT SKYBLUE (-450 2850);
FORCEPROP 1 LAST VOLTAGE 4V
J 0
(-450 2900);
DISPLAY 0.617021 (-450 2900);
PAINT SKYBLUE (-450 2900);
FORCEPROP 1 LASTPIN (-500 3000) $PN 1
J 0
(-490 2980);
DISPLAY 0.617021 (-490 2980);
PAINT ORANGE (-490 2980);
FORCEPROP 1 LAST PART_NUMBER E15431-001
J 0
(-450 2750);
DISPLAY 0.617021 (-450 2750);
PAINT BLUE (-450 2750);
FORCEPROP 2 LAST CDS_LIB mstr_discrete
J 0
(-500 2900);
PAINT ORANGE (-500 2900);
DISPLAY INVISIBLE (-500 2900);
FORCEPROP 2 LAST CDS_LOCATION C2D6
J 0
(-450 3000);
DISPLAY 0.617021 (-450 3000);
PAINT AQUA (-450 3000);
DISPLAY INVISIBLE (-450 3000);
FORCEPROP 2 LAST BOM_COST MEM_VRD_PVDDQ_KLM
J 0
(-450 3050);
PAINT MONO (-450 3050);
DISPLAY INVISIBLE (-450 3050);
FORCEPROP 1 LAST PATH I190
J 0
(-450 3050);
DISPLAY 0.978723 (-450 3050);
PAINT WHITE (-450 3050);
DISPLAY INVISIBLE (-450 3050);
FORCEPROP 2 LAST ROOM VDDQ_KLM_CPU1
J 0
(-450 3050);
PAINT MONO (-450 3050);
DISPLAY INVISIBLE (-450 3050);
FORCEPROP 2 LAST SEC_TYPE 0603LF
J 0
(-450 3100);
DISPLAY 1.021277 (-450 3100);
PAINT ORANGE (-450 3100);
DISPLAY INVISIBLE (-450 3100);
FORCEPROP 2 LAST SEC 1
J 0
(-450 3100);
DISPLAY 0.680851 (-450 3100);
PAINT MONO (-450 3100);
DISPLAY INVISIBLE (-450 3100);
FORCEADD PVDDQ_KLM..1
(-2300 3175);
FORCEPROP 3 LASTPIN (-2300 3125) SIG_NAME PVDDQ_KLM\g
J 0
(-2290 3135);
DISPLAY 0.659574 (-2290 3135);
PAINT MONO (-2290 3135);
DISPLAY INVISIBLE (-2290 3135);
FORCEPROP 1 LAST VOLTAGE 1.2V
J 0
(-2345 3132);
DISPLAY 0.340426 (-2345 3132);
PAINT SKYBLUE (-2345 3132);
DISPLAY INVISIBLE (-2345 3132);
FORCEPROP 1 LAST PATH I191
J 0
(-2250 3200);
DISPLAY 0.872340 (-2250 3200);
PAINT AQUA (-2250 3200);
DISPLAY INVISIBLE (-2250 3200);
FORCEPROP 2 LAST CDS_LIB mstr_symbols
J 0
(-2300 3175);
PAINT ORANGE (-2300 3175);
DISPLAY INVISIBLE (-2300 3175);
FORCEPROP 2 LAST BOM_COST MEM_VRD_PVPP_AB
J 0
(-2250 3275);
PAINT MONO (-2250 3275);
DISPLAY INVISIBLE (-2250 3275);
FORCEPROP 2 LAST ROOM VDDQ_KLM_PWR_VR
J 0
(-2075 3275);
PAINT ORANGE (-2075 3275);
DISPLAY INVISIBLE (-2075 3275);
FORCEPROP 1 LAST BODY_TYPE PLUMBING
J 0
(-2345 3132);
DISPLAY 0.340426 (-2345 3132);
PAINT GREEN (-2345 3132);
DISPLAY INVISIBLE (-2345 3132);
FORCEPROP 1 LAST HDL_POWER PVDDQ_KLM
J 1
(-2300 3225);
DISPLAY 0.872340 (-2300 3225);
PAINT GREEN (-2300 3225);
DISPLAY INVISIBLE (-2300 3225);
FORCEADD PVDDQ_KLM..1
(2550 1000);
FORCEPROP 3 LASTPIN (2550 950) SIG_NAME PVDDQ_KLM\g
J 0
(2560 960);
DISPLAY 0.659574 (2560 960);
PAINT MONO (2560 960);
DISPLAY INVISIBLE (2560 960);
FORCEPROP 1 LAST VOLTAGE 1.2V
J 0
(2505 957);
DISPLAY 0.340426 (2505 957);
PAINT SKYBLUE (2505 957);
DISPLAY INVISIBLE (2505 957);
FORCEPROP 2 LAST CDS_LIB mstr_symbols
J 0
(2550 1000);
PAINT ORANGE (2550 1000);
DISPLAY INVISIBLE (2550 1000);
FORCEPROP 2 LAST BOM_COST MEM_VRD_PVDDQ_CD
J 0
(2625 1100);
PAINT MONO (2625 1100);
DISPLAY INVISIBLE (2625 1100);
FORCEPROP 1 LAST PATH I195
J 0
(2600 1025);
DISPLAY 0.872340 (2600 1025);
PAINT AQUA (2600 1025);
DISPLAY INVISIBLE (2600 1025);
FORCEPROP 2 LAST ROOM VDDQ_KLM_PWR_VR
J 0
(2800 1100);
PAINT ORANGE (2800 1100);
DISPLAY INVISIBLE (2800 1100);
FORCEPROP 1 LAST BODY_TYPE PLUMBING
J 0
(2505 957);
DISPLAY 0.340426 (2505 957);
PAINT GREEN (2505 957);
DISPLAY INVISIBLE (2505 957);
FORCEPROP 1 LAST HDL_POWER PVDDQ_KLM
J 1
(2550 1050);
DISPLAY 0.872340 (2550 1050);
PAINT GREEN (2550 1050);
DISPLAY INVISIBLE (2550 1050);
FORCEADD GND..1
(3300 325);
FORCEPROP 3 LASTPIN (3300 375) SIG_NAME GND\g
J 0
(3310 385);
DISPLAY 0.659574 (3310 385);
PAINT MONO (3310 385);
DISPLAY INVISIBLE (3310 385);
FORCEPROP 2 LAST BOM_COST MEM_VRD_PVDDQ_CD
J 0
(2975 400);
PAINT MONO (2975 400);
DISPLAY INVISIBLE (2975 400);
FORCEPROP 2 LAST ROOM VDDQ_KLM_PWR_VR
J 0
(2750 400);
PAINT ORANGE (2750 400);
DISPLAY INVISIBLE (2750 400);
FORCEPROP 1 LAST VOLTAGE 0
J 0
(3300 325);
PAINT SKYBLUE (3300 325);
DISPLAY INVISIBLE (3300 325);
FORCEPROP 2 LAST CDS_LIB mstr_symbols
J 0
(3300 325);
PAINT ORANGE (3300 325);
DISPLAY INVISIBLE (3300 325);
FORCEPROP 1 LAST PATH I197
J 0
(3375 325);
DISPLAY 0.872340 (3375 325);
PAINT AQUA (3375 325);
DISPLAY INVISIBLE (3375 325);
FORCEPROP 1 LAST SIZE 1B
J 0
(3375 275);
DISPLAY 0.893617 (3375 275);
PAINT GREEN (3375 275);
DISPLAY INVISIBLE (3375 275);
FORCEPROP 1 LAST BODY_TYPE PLUMBING
J 0
(3255 282);
DISPLAY 0.340426 (3255 282);
PAINT GREEN (3255 282);
DISPLAY INVISIBLE (3255 282);
FORCEPROP 1 LAST HDL_POWER GND
J 0
(3300 475);
DISPLAY 0.893617 (3300 475);
PAINT GREEN (3300 475);
DISPLAY INVISIBLE (3300 475);
FORCEADD CAP_A..1
(2550 725);
FORCEPROP 1 LASTPIN (2550 825) $PN 1
J 0
(2560 805);
DISPLAY 0.617021 (2560 805);
PAINT ORANGE (2560 805);
FORCEPROP 1 LASTPIN (2550 625) $PN 2
J 0
(2560 605);
DISPLAY 0.617021 (2560 605);
PAINT ORANGE (2560 605);
FORCEPROP 1 LAST LOCATION C8M8
J 0
(2600 825);
DISPLAY 0.617021 (2600 825);
PAINT AQUA (2600 825);
FORCEPROP 1 LAST VALUE 47UF
J 0
(2600 775);
DISPLAY 0.617021 (2600 775);
PAINT SKYBLUE (2600 775);
FORCEPROP 1 LAST TOLERANCE 20%
J 0
(2600 675);
DISPLAY 0.617021 (2600 675);
PAINT SKYBLUE (2600 675);
FORCEPROP 1 LAST PACK_TYPE 0603V
J 0
(2600 525);
DISPLAY 0.617021 (2600 525);
PAINT SKYBLUE (2600 525);
FORCEPROP 1 LAST VOLTAGE 4V
J 0
(2600 725);
DISPLAY 0.617021 (2600 725);
PAINT SKYBLUE (2600 725);
FORCEPROP 1 LAST MATERIAL X5R
J 0
(2600 625);
DISPLAY 0.617021 (2600 625);
PAINT SKYBLUE (2600 625);
FORCEPROP 1 LAST PART_NUMBER 602433-106
J 0
(2600 575);
DISPLAY 0.617021 (2600 575);
PAINT BLUE (2600 575);
FORCEPROP 2 LAST CDS_LIB dev_discrete
J 0
(2550 725);
PAINT ORANGE (2550 725);
DISPLAY INVISIBLE (2550 725);
FORCEPROP 2 LAST CDS_LOCATION C8M8
J 0
(2600 825);
DISPLAY 0.617021 (2600 825);
PAINT AQUA (2600 825);
DISPLAY INVISIBLE (2600 825);
FORCEPROP 2 LAST CDS_SEC 1
J 0
(2600 875);
PAINT ORANGE (2600 875);
DISPLAY INVISIBLE (2600 875);
FORCEPROP 2 LAST SEC_TYPE 0603V
J 0
(2600 925);
DISPLAY 1.021277 (2600 925);
PAINT ORANGE (2600 925);
DISPLAY INVISIBLE (2600 925);
FORCEPROP 2 LAST SEC 1
J 0
(2600 925);
DISPLAY 0.680851 (2600 925);
PAINT MONO (2600 925);
DISPLAY INVISIBLE (2600 925);
FORCEPROP 1 LAST PATH I198
J 0
(2600 875);
DISPLAY 0.978723 (2600 875);
PAINT WHITE (2600 875);
DISPLAY INVISIBLE (2600 875);
FORCEADD CAP_A..1
(2900 725);
FORCEPROP 1 LASTPIN (2900 625) $PN 2
J 0
(2910 605);
DISPLAY 0.617021 (2910 605);
PAINT ORANGE (2910 605);
FORCEPROP 1 LAST MATERIAL X5R
J 0
(2950 625);
DISPLAY 0.617021 (2950 625);
PAINT SKYBLUE (2950 625);
FORCEPROP 1 LAST VOLTAGE 4V
J 0
(2950 725);
DISPLAY 0.617021 (2950 725);
PAINT SKYBLUE (2950 725);
FORCEPROP 1 LAST TOLERANCE 20%
J 0
(2950 675);
DISPLAY 0.617021 (2950 675);
PAINT SKYBLUE (2950 675);
FORCEPROP 1 LASTPIN (2900 825) $PN 1
J 0
(2910 805);
DISPLAY 0.617021 (2910 805);
PAINT ORANGE (2910 805);
FORCEPROP 1 LAST LOCATION C2A5
J 0
(2950 825);
DISPLAY 0.617021 (2950 825);
PAINT AQUA (2950 825);
FORCEPROP 1 LAST VALUE 47UF
J 0
(2950 775);
DISPLAY 0.617021 (2950 775);
PAINT SKYBLUE (2950 775);
FORCEPROP 1 LAST PART_NUMBER 602433-106
J 0
(2950 575);
DISPLAY 0.617021 (2950 575);
PAINT BLUE (2950 575);
FORCEPROP 1 LAST PACK_TYPE 0603V
J 0
(2950 525);
DISPLAY 0.617021 (2950 525);
PAINT SKYBLUE (2950 525);
FORCEPROP 2 LAST CDS_LIB dev_discrete
J 0
(2900 725);
PAINT ORANGE (2900 725);
DISPLAY INVISIBLE (2900 725);
FORCEPROP 1 LAST PATH I199
J 0
(2950 875);
DISPLAY 0.978723 (2950 875);
PAINT WHITE (2950 875);
DISPLAY INVISIBLE (2950 875);
FORCEPROP 2 LAST SEC 1
J 0
(2950 925);
DISPLAY 0.680851 (2950 925);
PAINT MONO (2950 925);
DISPLAY INVISIBLE (2950 925);
FORCEPROP 2 LAST SEC_TYPE 0603V
J 0
(2950 925);
DISPLAY 1.021277 (2950 925);
PAINT ORANGE (2950 925);
DISPLAY INVISIBLE (2950 925);
FORCEPROP 2 LAST CDS_SEC 1
J 0
(2950 875);
PAINT ORANGE (2950 875);
DISPLAY INVISIBLE (2950 875);
FORCEPROP 2 LAST CDS_LOCATION C2A5
J 0
(2950 825);
DISPLAY 0.617021 (2950 825);
PAINT AQUA (2950 825);
DISPLAY INVISIBLE (2950 825);
FORCEADD CAP_A..1
(3300 725);
FORCEPROP 1 LASTPIN (3300 625) $PN 2
J 0
(3310 605);
DISPLAY 0.617021 (3310 605);
PAINT ORANGE (3310 605);
FORCEPROP 1 LASTPIN (3300 825) $PN 1
J 0
(3310 805);
DISPLAY 0.617021 (3310 805);
PAINT ORANGE (3310 805);
FORCEPROP 1 LAST MATERIAL X5R
J 0
(3350 625);
DISPLAY 0.617021 (3350 625);
PAINT SKYBLUE (3350 625);
FORCEPROP 1 LAST VOLTAGE 4V
J 0
(3350 725);
DISPLAY 0.617021 (3350 725);
PAINT SKYBLUE (3350 725);
FORCEPROP 1 LAST PACK_TYPE 0603V
J 0
(3350 525);
DISPLAY 0.617021 (3350 525);
PAINT SKYBLUE (3350 525);
FORCEPROP 1 LAST TOLERANCE 20%
J 0
(3350 675);
DISPLAY 0.617021 (3350 675);
PAINT SKYBLUE (3350 675);
FORCEPROP 1 LAST VALUE 47UF
J 0
(3350 775);
DISPLAY 0.617021 (3350 775);
PAINT SKYBLUE (3350 775);
FORCEPROP 1 LAST LOCATION C2B1
J 0
(3350 825);
DISPLAY 0.617021 (3350 825);
PAINT AQUA (3350 825);
FORCEPROP 1 LAST PART_NUMBER 602433-106
J 0
(3350 575);
DISPLAY 0.617021 (3350 575);
PAINT BLUE (3350 575);
FORCEPROP 2 LAST CDS_LIB dev_discrete
J 0
(3300 725);
PAINT ORANGE (3300 725);
DISPLAY INVISIBLE (3300 725);
FORCEPROP 2 LAST CDS_LOCATION C2B1
J 0
(3350 825);
DISPLAY 0.617021 (3350 825);
PAINT AQUA (3350 825);
DISPLAY INVISIBLE (3350 825);
FORCEPROP 2 LAST CDS_SEC 1
J 0
(3350 875);
PAINT ORANGE (3350 875);
DISPLAY INVISIBLE (3350 875);
FORCEPROP 2 LAST SEC_TYPE 0603V
J 0
(3350 925);
DISPLAY 1.021277 (3350 925);
PAINT ORANGE (3350 925);
DISPLAY INVISIBLE (3350 925);
FORCEPROP 2 LAST SEC 1
J 0
(3350 925);
DISPLAY 0.680851 (3350 925);
PAINT MONO (3350 925);
DISPLAY INVISIBLE (3350 925);
FORCEPROP 1 LAST PATH I200
J 0
(3350 875);
DISPLAY 0.978723 (3350 875);
PAINT WHITE (3350 875);
DISPLAY INVISIBLE (3350 875);
FORCEADD CAP_A..1
(2525 1425);
FORCEPROP 1 LASTPIN (2525 1525) $PN 1
J 0
(2535 1505);
DISPLAY 0.617021 (2535 1505);
PAINT ORANGE (2535 1505);
FORCEPROP 1 LASTPIN (2525 1325) $PN 2
J 0
(2535 1305);
DISPLAY 0.617021 (2535 1305);
PAINT ORANGE (2535 1305);
FORCEPROP 1 LAST VALUE 47UF
J 0
(2575 1475);
DISPLAY 0.617021 (2575 1475);
PAINT SKYBLUE (2575 1475);
FORCEPROP 1 LAST TOLERANCE 20%
J 0
(2575 1375);
DISPLAY 0.617021 (2575 1375);
PAINT SKYBLUE (2575 1375);
FORCEPROP 1 LAST PACK_TYPE 0603V
J 0
(2575 1225);
DISPLAY 0.617021 (2575 1225);
PAINT SKYBLUE (2575 1225);
FORCEPROP 1 LAST VOLTAGE 4V
J 0
(2575 1425);
DISPLAY 0.617021 (2575 1425);
PAINT SKYBLUE (2575 1425);
FORCEPROP 1 LAST MATERIAL X5R
J 0
(2575 1325);
DISPLAY 0.617021 (2575 1325);
PAINT SKYBLUE (2575 1325);
FORCEPROP 1 LAST PART_NUMBER 602433-106
J 0
(2575 1275);
DISPLAY 0.617021 (2575 1275);
PAINT BLUE (2575 1275);
FORCEPROP 1 LAST LOCATION C8L12
J 0
(2575 1525);
DISPLAY 0.617021 (2575 1525);
PAINT AQUA (2575 1525);
FORCEPROP 2 LAST CDS_LIB dev_discrete
J 0
(2525 1425);
PAINT ORANGE (2525 1425);
DISPLAY INVISIBLE (2525 1425);
FORCEPROP 2 LAST CDS_LOCATION C8L12
J 0
(2575 1525);
DISPLAY 0.617021 (2575 1525);
PAINT AQUA (2575 1525);
DISPLAY INVISIBLE (2575 1525);
FORCEPROP 1 LAST PATH I201
J 0
(2575 1575);
DISPLAY 0.978723 (2575 1575);
PAINT WHITE (2575 1575);
DISPLAY INVISIBLE (2575 1575);
FORCEPROP 2 LAST SEC 1
J 0
(2575 1625);
DISPLAY 0.680851 (2575 1625);
PAINT MONO (2575 1625);
DISPLAY INVISIBLE (2575 1625);
FORCEPROP 2 LAST SEC_TYPE 0603V
J 0
(2575 1625);
DISPLAY 1.021277 (2575 1625);
PAINT ORANGE (2575 1625);
DISPLAY INVISIBLE (2575 1625);
FORCEPROP 2 LAST CDS_SEC 1
J 0
(2575 1575);
PAINT ORANGE (2575 1575);
DISPLAY INVISIBLE (2575 1575);
FORCEADD CAP_A..1
(2875 1425);
FORCEPROP 1 LAST PACK_TYPE 0603V
J 0
(2925 1225);
DISPLAY 0.617021 (2925 1225);
PAINT SKYBLUE (2925 1225);
FORCEPROP 1 LASTPIN (2875 1325) $PN 2
J 0
(2885 1305);
DISPLAY 0.617021 (2885 1305);
PAINT ORANGE (2885 1305);
FORCEPROP 1 LASTPIN (2875 1525) $PN 1
J 0
(2885 1505);
DISPLAY 0.617021 (2885 1505);
PAINT ORANGE (2885 1505);
FORCEPROP 1 LAST MATERIAL X5R
J 0
(2925 1325);
DISPLAY 0.617021 (2925 1325);
PAINT SKYBLUE (2925 1325);
FORCEPROP 1 LAST VOLTAGE 4V
J 0
(2925 1425);
DISPLAY 0.617021 (2925 1425);
PAINT SKYBLUE (2925 1425);
FORCEPROP 1 LAST TOLERANCE 20%
J 0
(2925 1375);
DISPLAY 0.617021 (2925 1375);
PAINT SKYBLUE (2925 1375);
FORCEPROP 1 LAST VALUE 47UF
J 0
(2925 1475);
DISPLAY 0.617021 (2925 1475);
PAINT SKYBLUE (2925 1475);
FORCEPROP 1 LAST LOCATION C7M5
J 0
(2925 1525);
DISPLAY 0.617021 (2925 1525);
PAINT AQUA (2925 1525);
FORCEPROP 1 LAST PART_NUMBER 602433-106
J 0
(2925 1275);
DISPLAY 0.617021 (2925 1275);
PAINT BLUE (2925 1275);
FORCEPROP 2 LAST CDS_LIB dev_discrete
J 0
(2875 1425);
PAINT ORANGE (2875 1425);
DISPLAY INVISIBLE (2875 1425);
FORCEPROP 2 LAST CDS_LOCATION C7M5
J 0
(2925 1525);
DISPLAY 0.617021 (2925 1525);
PAINT AQUA (2925 1525);
DISPLAY INVISIBLE (2925 1525);
FORCEPROP 1 LAST PATH I202
J 0
(2925 1575);
DISPLAY 0.978723 (2925 1575);
PAINT WHITE (2925 1575);
DISPLAY INVISIBLE (2925 1575);
FORCEPROP 2 LAST SEC 1
J 0
(2925 1625);
DISPLAY 0.680851 (2925 1625);
PAINT MONO (2925 1625);
DISPLAY INVISIBLE (2925 1625);
FORCEPROP 2 LAST SEC_TYPE 0603V
J 0
(2925 1625);
DISPLAY 1.021277 (2925 1625);
PAINT ORANGE (2925 1625);
DISPLAY INVISIBLE (2925 1625);
FORCEPROP 2 LAST CDS_SEC 1
J 0
(2925 1575);
PAINT ORANGE (2925 1575);
DISPLAY INVISIBLE (2925 1575);
FORCEADD CAP_A..1
(3275 1425);
FORCEPROP 1 LASTPIN (3275 1325) $PN 2
J 0
(3285 1305);
DISPLAY 0.617021 (3285 1305);
PAINT ORANGE (3285 1305);
FORCEPROP 1 LASTPIN (3275 1525) $PN 1
J 0
(3285 1505);
DISPLAY 0.617021 (3285 1505);
PAINT ORANGE (3285 1505);
FORCEPROP 1 LAST VALUE 47UF
J 0
(3325 1475);
DISPLAY 0.617021 (3325 1475);
PAINT SKYBLUE (3325 1475);
FORCEPROP 1 LAST TOLERANCE 20%
J 0
(3325 1375);
DISPLAY 0.617021 (3325 1375);
PAINT SKYBLUE (3325 1375);
FORCEPROP 1 LAST PACK_TYPE 0603V
J 0
(3325 1225);
DISPLAY 0.617021 (3325 1225);
PAINT SKYBLUE (3325 1225);
FORCEPROP 1 LAST VOLTAGE 4V
J 0
(3325 1425);
DISPLAY 0.617021 (3325 1425);
PAINT SKYBLUE (3325 1425);
FORCEPROP 1 LAST MATERIAL X5R
J 0
(3325 1325);
DISPLAY 0.617021 (3325 1325);
PAINT SKYBLUE (3325 1325);
FORCEPROP 1 LAST LOCATION C8M10
J 0
(3325 1525);
DISPLAY 0.617021 (3325 1525);
PAINT AQUA (3325 1525);
FORCEPROP 1 LAST PART_NUMBER 602433-106
J 0
(3325 1275);
DISPLAY 0.617021 (3325 1275);
PAINT BLUE (3325 1275);
FORCEPROP 2 LAST CDS_LIB dev_discrete
J 0
(3275 1425);
PAINT ORANGE (3275 1425);
DISPLAY INVISIBLE (3275 1425);
FORCEPROP 2 LAST CDS_LOCATION C8M10
J 0
(3325 1525);
DISPLAY 0.617021 (3325 1525);
PAINT AQUA (3325 1525);
DISPLAY INVISIBLE (3325 1525);
FORCEPROP 2 LAST CDS_SEC 1
J 0
(3325 1575);
PAINT ORANGE (3325 1575);
DISPLAY INVISIBLE (3325 1575);
FORCEPROP 2 LAST SEC_TYPE 0603V
J 0
(3325 1625);
DISPLAY 1.021277 (3325 1625);
PAINT ORANGE (3325 1625);
DISPLAY INVISIBLE (3325 1625);
FORCEPROP 2 LAST SEC 1
J 0
(3325 1625);
DISPLAY 0.680851 (3325 1625);
PAINT MONO (3325 1625);
DISPLAY INVISIBLE (3325 1625);
FORCEPROP 1 LAST PATH I203
J 0
(3325 1575);
DISPLAY 0.978723 (3325 1575);
PAINT WHITE (3325 1575);
DISPLAY INVISIBLE (3325 1575);
FORCEADD CAP_A..1
(3625 1425);
FORCEPROP 1 LAST PACK_TYPE 0603V
J 0
(3675 1225);
DISPLAY 0.617021 (3675 1225);
PAINT SKYBLUE (3675 1225);
FORCEPROP 1 LASTPIN (3625 1325) $PN 2
J 0
(3635 1305);
DISPLAY 0.617021 (3635 1305);
PAINT ORANGE (3635 1305);
FORCEPROP 1 LASTPIN (3625 1525) $PN 1
J 0
(3635 1505);
DISPLAY 0.617021 (3635 1505);
PAINT ORANGE (3635 1505);
FORCEPROP 1 LAST MATERIAL X5R
J 0
(3675 1325);
DISPLAY 0.617021 (3675 1325);
PAINT SKYBLUE (3675 1325);
FORCEPROP 1 LAST VOLTAGE 4V
J 0
(3675 1425);
DISPLAY 0.617021 (3675 1425);
PAINT SKYBLUE (3675 1425);
FORCEPROP 1 LAST TOLERANCE 20%
J 0
(3675 1375);
DISPLAY 0.617021 (3675 1375);
PAINT SKYBLUE (3675 1375);
FORCEPROP 1 LAST VALUE 47UF
J 0
(3675 1475);
DISPLAY 0.617021 (3675 1475);
PAINT SKYBLUE (3675 1475);
FORCEPROP 1 LAST PART_NUMBER 602433-106
J 0
(3675 1275);
DISPLAY 0.617021 (3675 1275);
PAINT BLUE (3675 1275);
FORCEPROP 1 LAST LOCATION C2B2
J 0
(3675 1525);
DISPLAY 0.617021 (3675 1525);
PAINT AQUA (3675 1525);
FORCEPROP 2 LAST CDS_LIB dev_discrete
J 0
(3625 1425);
PAINT ORANGE (3625 1425);
DISPLAY INVISIBLE (3625 1425);
FORCEPROP 2 LAST CDS_LOCATION C2B2
J 0
(3675 1525);
DISPLAY 0.617021 (3675 1525);
PAINT AQUA (3675 1525);
DISPLAY INVISIBLE (3675 1525);
FORCEPROP 1 LAST PATH I204
J 0
(3675 1575);
DISPLAY 0.978723 (3675 1575);
PAINT WHITE (3675 1575);
DISPLAY INVISIBLE (3675 1575);
FORCEPROP 2 LAST SEC 1
J 0
(3675 1625);
DISPLAY 0.680851 (3675 1625);
PAINT MONO (3675 1625);
DISPLAY INVISIBLE (3675 1625);
FORCEPROP 2 LAST SEC_TYPE 0603V
J 0
(3675 1625);
DISPLAY 1.021277 (3675 1625);
PAINT ORANGE (3675 1625);
DISPLAY INVISIBLE (3675 1625);
FORCEPROP 2 LAST CDS_SEC 1
J 0
(3675 1575);
PAINT ORANGE (3675 1575);
DISPLAY INVISIBLE (3675 1575);
FORCEADD CAP_A..1
(3975 1425);
FORCEPROP 1 LASTPIN (3975 1325) $PN 2
J 0
(3985 1305);
DISPLAY 0.617021 (3985 1305);
PAINT ORANGE (3985 1305);
FORCEPROP 1 LASTPIN (3975 1525) $PN 1
J 0
(3985 1505);
DISPLAY 0.617021 (3985 1505);
PAINT ORANGE (3985 1505);
FORCEPROP 1 LAST VOLTAGE 4V
J 0
(4025 1425);
DISPLAY 0.617021 (4025 1425);
PAINT SKYBLUE (4025 1425);
FORCEPROP 1 LAST LOCATION C8M9
J 0
(4025 1525);
DISPLAY 0.617021 (4025 1525);
PAINT AQUA (4025 1525);
FORCEPROP 1 LAST PART_NUMBER 602433-106
J 0
(4025 1275);
DISPLAY 0.617021 (4025 1275);
PAINT BLUE (4025 1275);
FORCEPROP 1 LAST VALUE 47UF
J 0
(4025 1475);
DISPLAY 0.617021 (4025 1475);
PAINT SKYBLUE (4025 1475);
FORCEPROP 1 LAST TOLERANCE 20%
J 0
(4025 1375);
DISPLAY 0.617021 (4025 1375);
PAINT SKYBLUE (4025 1375);
FORCEPROP 1 LAST PACK_TYPE 0603V
J 0
(4025 1225);
DISPLAY 0.617021 (4025 1225);
PAINT SKYBLUE (4025 1225);
FORCEPROP 1 LAST MATERIAL X5R
J 0
(4025 1325);
DISPLAY 0.617021 (4025 1325);
PAINT SKYBLUE (4025 1325);
FORCEPROP 2 LAST CDS_LIB dev_discrete
J 0
(3975 1425);
PAINT ORANGE (3975 1425);
DISPLAY INVISIBLE (3975 1425);
FORCEPROP 2 LAST CDS_LOCATION C8M9
J 0
(4025 1525);
DISPLAY 0.617021 (4025 1525);
PAINT AQUA (4025 1525);
DISPLAY INVISIBLE (4025 1525);
FORCEPROP 1 LAST PATH I205
J 0
(4025 1575);
DISPLAY 0.978723 (4025 1575);
PAINT WHITE (4025 1575);
DISPLAY INVISIBLE (4025 1575);
FORCEPROP 2 LAST SEC 1
J 0
(4025 1625);
DISPLAY 0.680851 (4025 1625);
PAINT MONO (4025 1625);
DISPLAY INVISIBLE (4025 1625);
FORCEPROP 2 LAST SEC_TYPE 0603V
J 0
(4025 1625);
DISPLAY 1.021277 (4025 1625);
PAINT ORANGE (4025 1625);
DISPLAY INVISIBLE (4025 1625);
FORCEPROP 2 LAST CDS_SEC 1
J 0
(4025 1575);
PAINT ORANGE (4025 1575);
DISPLAY INVISIBLE (4025 1575);
FORCEADD CAP_A..1
(4375 1425);
FORCEPROP 1 LAST PACK_TYPE 0603V
J 0
(4425 1225);
DISPLAY 0.617021 (4425 1225);
PAINT SKYBLUE (4425 1225);
FORCEPROP 1 LASTPIN (4375 1325) $PN 2
J 0
(4385 1305);
DISPLAY 0.617021 (4385 1305);
PAINT ORANGE (4385 1305);
FORCEPROP 1 LASTPIN (4375 1525) $PN 1
J 0
(4385 1505);
DISPLAY 0.617021 (4385 1505);
PAINT ORANGE (4385 1505);
FORCEPROP 1 LAST MATERIAL X5R
J 0
(4425 1325);
DISPLAY 0.617021 (4425 1325);
PAINT SKYBLUE (4425 1325);
FORCEPROP 1 LAST VOLTAGE 4V
J 0
(4425 1425);
DISPLAY 0.617021 (4425 1425);
PAINT SKYBLUE (4425 1425);
FORCEPROP 1 LAST TOLERANCE 20%
J 0
(4425 1375);
DISPLAY 0.617021 (4425 1375);
PAINT SKYBLUE (4425 1375);
FORCEPROP 1 LAST VALUE 47UF
J 0
(4425 1475);
DISPLAY 0.617021 (4425 1475);
PAINT SKYBLUE (4425 1475);
FORCEPROP 1 LAST LOCATION C8M2
J 0
(4425 1525);
DISPLAY 0.617021 (4425 1525);
PAINT AQUA (4425 1525);
FORCEPROP 1 LAST PART_NUMBER 602433-106
J 0
(4425 1275);
DISPLAY 0.617021 (4425 1275);
PAINT BLUE (4425 1275);
FORCEPROP 2 LAST CDS_LIB dev_discrete
J 0
(4375 1425);
PAINT ORANGE (4375 1425);
DISPLAY INVISIBLE (4375 1425);
FORCEPROP 2 LAST CDS_LOCATION C8M2
J 0
(4425 1525);
DISPLAY 0.617021 (4425 1525);
PAINT AQUA (4425 1525);
DISPLAY INVISIBLE (4425 1525);
FORCEPROP 2 LAST CDS_SEC 1
J 0
(4425 1575);
PAINT ORANGE (4425 1575);
DISPLAY INVISIBLE (4425 1575);
FORCEPROP 2 LAST SEC_TYPE 0603V
J 0
(4425 1625);
DISPLAY 1.021277 (4425 1625);
PAINT ORANGE (4425 1625);
DISPLAY INVISIBLE (4425 1625);
FORCEPROP 2 LAST SEC 1
J 0
(4425 1625);
DISPLAY 0.680851 (4425 1625);
PAINT MONO (4425 1625);
DISPLAY INVISIBLE (4425 1625);
FORCEPROP 1 LAST PATH I206
J 0
(4425 1575);
DISPLAY 0.978723 (4425 1575);
PAINT WHITE (4425 1575);
DISPLAY INVISIBLE (4425 1575);
FORCEADD PVDDQ_KLM..1
(-1550 3175);
FORCEPROP 3 LASTPIN (-1550 3125) SIG_NAME PVDDQ_KLM\g
J 0
(-1540 3135);
DISPLAY 0.659574 (-1540 3135);
PAINT MONO (-1540 3135);
DISPLAY INVISIBLE (-1540 3135);
FORCEPROP 2 LAST CDS_LIB mstr_symbols
J 0
(-1550 3175);
PAINT ORANGE (-1550 3175);
DISPLAY INVISIBLE (-1550 3175);
FORCEPROP 1 LAST VOLTAGE 1.2V
J 0
(-1595 3132);
DISPLAY 0.340426 (-1595 3132);
PAINT SKYBLUE (-1595 3132);
DISPLAY INVISIBLE (-1595 3132);
FORCEPROP 2 LAST ROOM VDDQ_KLM_PWR_VR
J 0
(-1325 3275);
PAINT ORANGE (-1325 3275);
DISPLAY INVISIBLE (-1325 3275);
FORCEPROP 1 LAST PATH I207
J 0
(-1500 3200);
DISPLAY 0.872340 (-1500 3200);
PAINT AQUA (-1500 3200);
DISPLAY INVISIBLE (-1500 3200);
FORCEPROP 2 LAST BOM_COST MEM_VRD_PVPP_AB
J 0
(-1500 3275);
PAINT MONO (-1500 3275);
DISPLAY INVISIBLE (-1500 3275);
FORCEPROP 1 LAST BODY_TYPE PLUMBING
J 0
(-1595 3132);
DISPLAY 0.340426 (-1595 3132);
PAINT GREEN (-1595 3132);
DISPLAY INVISIBLE (-1595 3132);
FORCEPROP 1 LAST HDL_POWER PVDDQ_KLM
J 1
(-1550 3225);
DISPLAY 0.872340 (-1550 3225);
PAINT GREEN (-1550 3225);
DISPLAY INVISIBLE (-1550 3225);
FORCEADD GND..1
(-1900 2525);
FORCEPROP 3 LASTPIN (-1900 2575) SIG_NAME GND\g
J 0
(-1890 2585);
DISPLAY 0.659574 (-1890 2585);
PAINT MONO (-1890 2585);
DISPLAY INVISIBLE (-1890 2585);
FORCEPROP 2 LAST ROOM VDDQ_ABC_PWR_VR
J 0
(-2450 2600);
PAINT ORANGE (-2450 2600);
DISPLAY INVISIBLE (-2450 2600);
FORCEPROP 2 LAST BOM_COST MEM_VRD_PVDDQ_CD
J 0
(-2225 2600);
PAINT MONO (-2225 2600);
DISPLAY INVISIBLE (-2225 2600);
FORCEPROP 1 LAST SIZE 1B
J 0
(-1825 2475);
DISPLAY 0.893617 (-1825 2475);
PAINT GREEN (-1825 2475);
DISPLAY INVISIBLE (-1825 2475);
FORCEPROP 1 LAST VOLTAGE 0
J 0
(-1900 2525);
PAINT SKYBLUE (-1900 2525);
DISPLAY INVISIBLE (-1900 2525);
FORCEPROP 2 LAST CDS_LIB mstr_symbols
J 0
(-1900 2525);
PAINT ORANGE (-1900 2525);
DISPLAY INVISIBLE (-1900 2525);
FORCEPROP 1 LAST PATH I208
J 0
(-1825 2525);
DISPLAY 0.872340 (-1825 2525);
PAINT AQUA (-1825 2525);
DISPLAY INVISIBLE (-1825 2525);
FORCEPROP 1 LAST BODY_TYPE PLUMBING
J 0
(-1945 2482);
DISPLAY 0.340426 (-1945 2482);
PAINT GREEN (-1945 2482);
DISPLAY INVISIBLE (-1945 2482);
FORCEPROP 1 LAST HDL_POWER GND
J 0
(-1900 2675);
DISPLAY 0.893617 (-1900 2675);
PAINT GREEN (-1900 2675);
DISPLAY INVISIBLE (-1900 2675);
FORCEADD CAP_A..1
(2125 -75);
FORCEPROP 1 LASTPIN (2125 -175) $PN 2
J 0
(2135 -195);
DISPLAY 0.617021 (2135 -195);
PAINT ORANGE (2135 -195);
FORCEPROP 1 LAST MATERIAL X6S
J 0
(2175 -175);
DISPLAY 0.617021 (2175 -175);
PAINT SKYBLUE (2175 -175);
FORCEPROP 1 LAST VOLTAGE 4V
J 0
(2175 -75);
DISPLAY 0.617021 (2175 -75);
PAINT SKYBLUE (2175 -75);
FORCEPROP 1 LAST TOLERANCE 20%
J 0
(2175 -125);
DISPLAY 0.617021 (2175 -125);
PAINT SKYBLUE (2175 -125);
FORCEPROP 1 LAST PACK_TYPE 0603V
J 0
(2175 -275);
DISPLAY 0.617021 (2175 -275);
PAINT SKYBLUE (2175 -275);
FORCEPROP 1 LAST PART_NUMBER E15431-004
J 0
(2175 -225);
DISPLAY 0.617021 (2175 -225);
PAINT BLUE (2175 -225);
FORCEPROP 1 LAST VALUE 22.0UF
J 0
(2175 -25);
DISPLAY 0.617021 (2175 -25);
PAINT SKYBLUE (2175 -25);
FORCEPROP 1 LAST LOCATION C2A2
J 0
(2175 25);
DISPLAY 0.617021 (2175 25);
PAINT AQUA (2175 25);
FORCEPROP 1 LASTPIN (2125 25) $PN 1
J 0
(2135 5);
DISPLAY 0.617021 (2135 5);
PAINT ORANGE (2135 5);
FORCEPROP 2 LAST CDS_LIB dev_discrete
J 0
(2125 -75);
PAINT ORANGE (2125 -75);
DISPLAY INVISIBLE (2125 -75);
FORCEPROP 2 LAST CDS_SEC 1
J 0
(2175 75);
PAINT ORANGE (2175 75);
DISPLAY INVISIBLE (2175 75);
FORCEPROP 2 LAST CDS_LOCATION C2A2
J 0
(2175 25);
DISPLAY 0.617021 (2175 25);
PAINT AQUA (2175 25);
DISPLAY INVISIBLE (2175 25);
FORCEPROP 0 LAST ROOM PVDDQ_KLM
J 0
(2175 125);
DISPLAY 1.021277 (2175 125);
PAINT ORANGE (2175 125);
DISPLAY INVISIBLE (2175 125);
FORCEPROP 1 LAST PATH I209
J 0
(2175 75);
DISPLAY 0.978723 (2175 75);
PAINT WHITE (2175 75);
DISPLAY INVISIBLE (2175 75);
FORCEPROP 2 LAST SEC_TYPE 0603V
J 0
(2175 125);
DISPLAY 1.021277 (2175 125);
PAINT ORANGE (2175 125);
DISPLAY INVISIBLE (2175 125);
FORCEPROP 2 LAST SEC 1
J 0
(2175 125);
DISPLAY 0.680851 (2175 125);
PAINT MONO (2175 125);
DISPLAY INVISIBLE (2175 125);
FORCEADD CAP_A..1
(1850 -75);
FORCEPROP 1 LAST PACK_TYPE 0603V
J 0
(1900 -275);
DISPLAY 0.617021 (1900 -275);
PAINT SKYBLUE (1900 -275);
FORCEPROP 1 LASTPIN (1850 -175) $PN 2
J 0
(1860 -195);
DISPLAY 0.617021 (1860 -195);
PAINT ORANGE (1860 -195);
FORCEPROP 1 LAST TOLERANCE 20%
J 0
(1900 -125);
DISPLAY 0.617021 (1900 -125);
PAINT SKYBLUE (1900 -125);
FORCEPROP 1 LAST VOLTAGE 4V
J 0
(1900 -75);
DISPLAY 0.617021 (1900 -75);
PAINT SKYBLUE (1900 -75);
FORCEPROP 1 LAST MATERIAL X6S
J 0
(1900 -175);
DISPLAY 0.617021 (1900 -175);
PAINT SKYBLUE (1900 -175);
FORCEPROP 1 LAST PART_NUMBER E15431-004
J 0
(1900 -225);
DISPLAY 0.617021 (1900 -225);
PAINT BLUE (1900 -225);
FORCEPROP 1 LAST VALUE 22.0UF
J 0
(1900 -25);
DISPLAY 0.617021 (1900 -25);
PAINT SKYBLUE (1900 -25);
FORCEPROP 1 LASTPIN (1850 25) $PN 1
J 0
(1860 5);
DISPLAY 0.617021 (1860 5);
PAINT ORANGE (1860 5);
FORCEPROP 1 LAST LOCATION C2A1
J 0
(1900 25);
DISPLAY 0.617021 (1900 25);
PAINT AQUA (1900 25);
FORCEPROP 2 LAST CDS_LIB dev_discrete
J 0
(1850 -75);
PAINT ORANGE (1850 -75);
DISPLAY INVISIBLE (1850 -75);
FORCEPROP 1 LAST PATH I210
J 0
(1900 75);
DISPLAY 0.978723 (1900 75);
PAINT WHITE (1900 75);
DISPLAY INVISIBLE (1900 75);
FORCEPROP 2 LAST CDS_SEC 1
J 0
(1900 75);
PAINT ORANGE (1900 75);
DISPLAY INVISIBLE (1900 75);
FORCEPROP 2 LAST CDS_LOCATION C2A1
J 0
(1900 25);
DISPLAY 0.617021 (1900 25);
PAINT AQUA (1900 25);
DISPLAY INVISIBLE (1900 25);
FORCEPROP 0 LAST ROOM PVDDQ_KLM
J 0
(1900 125);
DISPLAY 1.021277 (1900 125);
PAINT ORANGE (1900 125);
DISPLAY INVISIBLE (1900 125);
FORCEPROP 2 LAST SEC 1
J 0
(1900 125);
DISPLAY 0.680851 (1900 125);
PAINT MONO (1900 125);
DISPLAY INVISIBLE (1900 125);
FORCEPROP 2 LAST SEC_TYPE 0603V
J 0
(1900 125);
DISPLAY 1.021277 (1900 125);
PAINT ORANGE (1900 125);
DISPLAY INVISIBLE (1900 125);
FORCEADD CAP_A..1
(1550 -75);
FORCEPROP 1 LAST PACK_TYPE 0603V
J 0
(1600 -275);
DISPLAY 0.617021 (1600 -275);
PAINT SKYBLUE (1600 -275);
FORCEPROP 1 LAST TOLERANCE 20%
J 0
(1600 -125);
DISPLAY 0.617021 (1600 -125);
PAINT SKYBLUE (1600 -125);
FORCEPROP 1 LAST VOLTAGE 4V
J 0
(1600 -75);
DISPLAY 0.617021 (1600 -75);
PAINT SKYBLUE (1600 -75);
FORCEPROP 1 LAST MATERIAL X6S
J 0
(1600 -175);
DISPLAY 0.617021 (1600 -175);
PAINT SKYBLUE (1600 -175);
FORCEPROP 1 LASTPIN (1550 -175) $PN 2
J 0
(1560 -195);
DISPLAY 0.617021 (1560 -195);
PAINT ORANGE (1560 -195);
FORCEPROP 1 LAST PART_NUMBER E15431-004
J 0
(1600 -225);
DISPLAY 0.617021 (1600 -225);
PAINT BLUE (1600 -225);
FORCEPROP 1 LAST VALUE 22.0UF
J 0
(1600 -25);
DISPLAY 0.617021 (1600 -25);
PAINT SKYBLUE (1600 -25);
FORCEPROP 1 LASTPIN (1550 25) $PN 1
J 0
(1560 5);
DISPLAY 0.617021 (1560 5);
PAINT ORANGE (1560 5);
FORCEPROP 1 LAST LOCATION C2A12
J 0
(1600 25);
DISPLAY 0.617021 (1600 25);
PAINT AQUA (1600 25);
FORCEPROP 2 LAST CDS_LIB dev_discrete
J 0
(1550 -75);
PAINT ORANGE (1550 -75);
DISPLAY INVISIBLE (1550 -75);
FORCEPROP 1 LAST PATH I211
J 0
(1600 75);
DISPLAY 0.978723 (1600 75);
PAINT WHITE (1600 75);
DISPLAY INVISIBLE (1600 75);
FORCEPROP 2 LAST CDS_SEC 1
J 0
(1600 75);
PAINT ORANGE (1600 75);
DISPLAY INVISIBLE (1600 75);
FORCEPROP 2 LAST CDS_LOCATION C2A12
J 0
(1600 25);
DISPLAY 0.617021 (1600 25);
PAINT AQUA (1600 25);
DISPLAY INVISIBLE (1600 25);
FORCEPROP 0 LAST ROOM PVDDQ_KLM
J 0
(1600 125);
DISPLAY 1.021277 (1600 125);
PAINT ORANGE (1600 125);
DISPLAY INVISIBLE (1600 125);
FORCEPROP 2 LAST SEC 1
J 0
(1600 125);
DISPLAY 0.680851 (1600 125);
PAINT MONO (1600 125);
DISPLAY INVISIBLE (1600 125);
FORCEPROP 2 LAST SEC_TYPE 0603V
J 0
(1600 125);
DISPLAY 1.021277 (1600 125);
PAINT ORANGE (1600 125);
DISPLAY INVISIBLE (1600 125);
FORCEADD CAP_A..1
(1250 -75);
FORCEPROP 1 LASTPIN (1250 -175) $PN 2
J 0
(1260 -195);
DISPLAY 0.617021 (1260 -195);
PAINT ORANGE (1260 -195);
FORCEPROP 1 LAST MATERIAL X6S
J 0
(1300 -175);
DISPLAY 0.617021 (1300 -175);
PAINT SKYBLUE (1300 -175);
FORCEPROP 1 LAST VOLTAGE 4V
J 0
(1300 -75);
DISPLAY 0.617021 (1300 -75);
PAINT SKYBLUE (1300 -75);
FORCEPROP 1 LAST PACK_TYPE 0603V
J 0
(1300 -275);
DISPLAY 0.617021 (1300 -275);
PAINT SKYBLUE (1300 -275);
FORCEPROP 1 LAST TOLERANCE 20%
J 0
(1300 -125);
DISPLAY 0.617021 (1300 -125);
PAINT SKYBLUE (1300 -125);
FORCEPROP 1 LAST PART_NUMBER E15431-004
J 0
(1300 -225);
DISPLAY 0.617021 (1300 -225);
PAINT BLUE (1300 -225);
FORCEPROP 1 LAST VALUE 22.0UF
J 0
(1300 -25);
DISPLAY 0.617021 (1300 -25);
PAINT SKYBLUE (1300 -25);
FORCEPROP 1 LASTPIN (1250 25) $PN 1
J 0
(1260 5);
DISPLAY 0.617021 (1260 5);
PAINT ORANGE (1260 5);
FORCEPROP 1 LAST LOCATION C2A13
J 0
(1300 25);
DISPLAY 0.617021 (1300 25);
PAINT AQUA (1300 25);
FORCEPROP 2 LAST CDS_LIB dev_discrete
J 0
(1250 -75);
PAINT ORANGE (1250 -75);
DISPLAY INVISIBLE (1250 -75);
FORCEPROP 2 LAST CDS_LOCATION C2A13
J 0
(1300 25);
DISPLAY 0.617021 (1300 25);
PAINT AQUA (1300 25);
DISPLAY INVISIBLE (1300 25);
FORCEPROP 2 LAST CDS_SEC 1
J 0
(1300 75);
PAINT ORANGE (1300 75);
DISPLAY INVISIBLE (1300 75);
FORCEPROP 2 LAST SEC_TYPE 0603V
J 0
(1300 125);
DISPLAY 1.021277 (1300 125);
PAINT ORANGE (1300 125);
DISPLAY INVISIBLE (1300 125);
FORCEPROP 2 LAST SEC 1
J 0
(1300 125);
DISPLAY 0.680851 (1300 125);
PAINT MONO (1300 125);
DISPLAY INVISIBLE (1300 125);
FORCEPROP 1 LAST PATH I212
J 0
(1300 75);
DISPLAY 0.978723 (1300 75);
PAINT WHITE (1300 75);
DISPLAY INVISIBLE (1300 75);
FORCEPROP 0 LAST ROOM PVDDQ_KLM
J 0
(1300 125);
DISPLAY 1.021277 (1300 125);
PAINT ORANGE (1300 125);
DISPLAY INVISIBLE (1300 125);
FORCEADD CAP_A..1
(975 -75);
FORCEPROP 1 LASTPIN (975 -175) $PN 2
J 0
(985 -195);
DISPLAY 0.617021 (985 -195);
PAINT ORANGE (985 -195);
FORCEPROP 1 LAST PACK_TYPE 0603V
J 0
(1025 -275);
DISPLAY 0.617021 (1025 -275);
PAINT SKYBLUE (1025 -275);
FORCEPROP 1 LAST TOLERANCE 20%
J 0
(1025 -125);
DISPLAY 0.617021 (1025 -125);
PAINT SKYBLUE (1025 -125);
FORCEPROP 1 LAST VOLTAGE 4V
J 0
(1025 -75);
DISPLAY 0.617021 (1025 -75);
PAINT SKYBLUE (1025 -75);
FORCEPROP 1 LAST MATERIAL X6S
J 0
(1025 -175);
DISPLAY 0.617021 (1025 -175);
PAINT SKYBLUE (1025 -175);
FORCEPROP 1 LAST PART_NUMBER E15431-004
J 0
(1025 -225);
DISPLAY 0.617021 (1025 -225);
PAINT BLUE (1025 -225);
FORCEPROP 1 LAST VALUE 22.0UF
J 0
(1025 -25);
DISPLAY 0.617021 (1025 -25);
PAINT SKYBLUE (1025 -25);
FORCEPROP 1 LASTPIN (975 25) $PN 1
J 0
(985 5);
DISPLAY 0.617021 (985 5);
PAINT ORANGE (985 5);
FORCEPROP 1 LAST LOCATION C2A11
J 0
(1025 25);
DISPLAY 0.617021 (1025 25);
PAINT AQUA (1025 25);
FORCEPROP 2 LAST CDS_LIB dev_discrete
J 0
(975 -75);
PAINT ORANGE (975 -75);
DISPLAY INVISIBLE (975 -75);
FORCEPROP 2 LAST CDS_LOCATION C2A11
J 0
(1025 25);
DISPLAY 0.617021 (1025 25);
PAINT AQUA (1025 25);
DISPLAY INVISIBLE (1025 25);
FORCEPROP 2 LAST CDS_SEC 1
J 0
(1025 75);
PAINT ORANGE (1025 75);
DISPLAY INVISIBLE (1025 75);
FORCEPROP 2 LAST SEC_TYPE 0603V
J 0
(1025 125);
DISPLAY 1.021277 (1025 125);
PAINT ORANGE (1025 125);
DISPLAY INVISIBLE (1025 125);
FORCEPROP 2 LAST SEC 1
J 0
(1025 125);
DISPLAY 0.680851 (1025 125);
PAINT MONO (1025 125);
DISPLAY INVISIBLE (1025 125);
FORCEPROP 1 LAST PATH I213
J 0
(1025 75);
DISPLAY 0.978723 (1025 75);
PAINT WHITE (1025 75);
DISPLAY INVISIBLE (1025 75);
FORCEPROP 0 LAST ROOM PVDDQ_KLM
J 0
(1025 125);
DISPLAY 1.021277 (1025 125);
PAINT ORANGE (1025 125);
DISPLAY INVISIBLE (1025 125);
FORCEADD CAP_A..1
(700 -75);
FORCEPROP 1 LASTPIN (700 -175) $PN 2
J 0
(710 -195);
DISPLAY 0.617021 (710 -195);
PAINT ORANGE (710 -195);
FORCEPROP 1 LAST MATERIAL X6S
J 0
(750 -175);
DISPLAY 0.617021 (750 -175);
PAINT SKYBLUE (750 -175);
FORCEPROP 1 LAST VOLTAGE 4V
J 0
(750 -75);
DISPLAY 0.617021 (750 -75);
PAINT SKYBLUE (750 -75);
FORCEPROP 1 LAST PACK_TYPE 0603V
J 0
(750 -275);
DISPLAY 0.617021 (750 -275);
PAINT SKYBLUE (750 -275);
FORCEPROP 1 LAST TOLERANCE 20%
J 0
(750 -125);
DISPLAY 0.617021 (750 -125);
PAINT SKYBLUE (750 -125);
FORCEPROP 1 LAST PART_NUMBER E15431-004
J 0
(750 -225);
DISPLAY 0.617021 (750 -225);
PAINT BLUE (750 -225);
FORCEPROP 1 LAST VALUE 22.0UF
J 0
(750 -25);
DISPLAY 0.617021 (750 -25);
PAINT SKYBLUE (750 -25);
FORCEPROP 1 LASTPIN (700 25) $PN 1
J 0
(710 5);
DISPLAY 0.617021 (710 5);
PAINT ORANGE (710 5);
FORCEPROP 1 LAST LOCATION C2A10
J 0
(750 25);
DISPLAY 0.617021 (750 25);
PAINT AQUA (750 25);
FORCEPROP 2 LAST CDS_LIB dev_discrete
J 0
(700 -75);
PAINT ORANGE (700 -75);
DISPLAY INVISIBLE (700 -75);
FORCEPROP 1 LAST PATH I214
J 0
(750 75);
DISPLAY 0.978723 (750 75);
PAINT WHITE (750 75);
DISPLAY INVISIBLE (750 75);
FORCEPROP 2 LAST CDS_SEC 1
J 0
(750 75);
PAINT ORANGE (750 75);
DISPLAY INVISIBLE (750 75);
FORCEPROP 2 LAST CDS_LOCATION C2A10
J 0
(750 25);
DISPLAY 0.617021 (750 25);
PAINT AQUA (750 25);
DISPLAY INVISIBLE (750 25);
FORCEPROP 0 LAST ROOM PVDDQ_KLM
J 0
(750 125);
DISPLAY 1.021277 (750 125);
PAINT ORANGE (750 125);
DISPLAY INVISIBLE (750 125);
FORCEPROP 2 LAST SEC 1
J 0
(750 125);
DISPLAY 0.680851 (750 125);
PAINT MONO (750 125);
DISPLAY INVISIBLE (750 125);
FORCEPROP 2 LAST SEC_TYPE 0603V
J 0
(750 125);
DISPLAY 1.021277 (750 125);
PAINT ORANGE (750 125);
DISPLAY INVISIBLE (750 125);
FORCEADD CAP_A..1
(400 -75);
FORCEPROP 1 LASTPIN (400 -175) $PN 2
J 0
(410 -195);
DISPLAY 0.617021 (410 -195);
PAINT ORANGE (410 -195);
FORCEPROP 1 LAST VOLTAGE 4V
J 0
(450 -75);
DISPLAY 0.617021 (450 -75);
PAINT SKYBLUE (450 -75);
FORCEPROP 1 LAST PART_NUMBER E15431-004
J 0
(450 -225);
DISPLAY 0.617021 (450 -225);
PAINT BLUE (450 -225);
FORCEPROP 1 LAST PACK_TYPE 0603V
J 0
(450 -275);
DISPLAY 0.617021 (450 -275);
PAINT SKYBLUE (450 -275);
FORCEPROP 1 LAST MATERIAL X6S
J 0
(450 -175);
DISPLAY 0.617021 (450 -175);
PAINT SKYBLUE (450 -175);
FORCEPROP 1 LAST VALUE 22.0UF
J 0
(450 -25);
DISPLAY 0.617021 (450 -25);
PAINT SKYBLUE (450 -25);
FORCEPROP 1 LASTPIN (400 25) $PN 1
J 0
(410 5);
DISPLAY 0.617021 (410 5);
PAINT ORANGE (410 5);
FORCEPROP 1 LAST LOCATION C2A9
J 0
(450 25);
DISPLAY 0.617021 (450 25);
PAINT AQUA (450 25);
FORCEPROP 1 LAST TOLERANCE 20%
J 0
(450 -125);
DISPLAY 0.617021 (450 -125);
PAINT SKYBLUE (450 -125);
FORCEPROP 2 LAST CDS_LIB dev_discrete
J 0
(400 -75);
PAINT ORANGE (400 -75);
DISPLAY INVISIBLE (400 -75);
FORCEPROP 1 LAST PATH I215
J 0
(450 75);
DISPLAY 0.978723 (450 75);
PAINT WHITE (450 75);
DISPLAY INVISIBLE (450 75);
FORCEPROP 2 LAST CDS_SEC 1
J 0
(450 75);
PAINT ORANGE (450 75);
DISPLAY INVISIBLE (450 75);
FORCEPROP 2 LAST CDS_LOCATION C2A9
J 0
(450 25);
DISPLAY 0.617021 (450 25);
PAINT AQUA (450 25);
DISPLAY INVISIBLE (450 25);
FORCEPROP 0 LAST ROOM PVDDQ_KLM
J 0
(450 125);
DISPLAY 1.021277 (450 125);
PAINT ORANGE (450 125);
DISPLAY INVISIBLE (450 125);
FORCEPROP 2 LAST SEC 1
J 0
(450 125);
DISPLAY 0.680851 (450 125);
PAINT MONO (450 125);
DISPLAY INVISIBLE (450 125);
FORCEPROP 2 LAST SEC_TYPE 0603V
J 0
(450 125);
DISPLAY 1.021277 (450 125);
PAINT ORANGE (450 125);
DISPLAY INVISIBLE (450 125);
FORCEADD CAP_A..1
(100 -75);
FORCEPROP 1 LASTPIN (100 -175) $PN 2
J 0
(110 -195);
DISPLAY 0.617021 (110 -195);
PAINT ORANGE (110 -195);
FORCEPROP 1 LAST VOLTAGE 4V
J 0
(150 -75);
DISPLAY 0.617021 (150 -75);
PAINT SKYBLUE (150 -75);
FORCEPROP 1 LAST TOLERANCE 20%
J 0
(150 -125);
DISPLAY 0.617021 (150 -125);
PAINT SKYBLUE (150 -125);
FORCEPROP 1 LAST PACK_TYPE 0603V
J 0
(150 -275);
DISPLAY 0.617021 (150 -275);
PAINT SKYBLUE (150 -275);
FORCEPROP 1 LAST PART_NUMBER E15431-004
J 0
(150 -225);
DISPLAY 0.617021 (150 -225);
PAINT BLUE (150 -225);
FORCEPROP 1 LAST VALUE 22.0UF
J 0
(150 -25);
DISPLAY 0.617021 (150 -25);
PAINT SKYBLUE (150 -25);
FORCEPROP 1 LASTPIN (100 25) $PN 1
J 0
(110 5);
DISPLAY 0.617021 (110 5);
PAINT ORANGE (110 5);
FORCEPROP 1 LAST LOCATION C3A2
J 0
(150 25);
DISPLAY 0.617021 (150 25);
PAINT AQUA (150 25);
FORCEPROP 1 LAST MATERIAL X6S
J 0
(150 -175);
DISPLAY 0.617021 (150 -175);
PAINT SKYBLUE (150 -175);
FORCEPROP 2 LAST CDS_LIB dev_discrete
J 0
(100 -75);
PAINT ORANGE (100 -75);
DISPLAY INVISIBLE (100 -75);
FORCEPROP 2 LAST SEC 1
J 0
(150 125);
DISPLAY 0.680851 (150 125);
PAINT MONO (150 125);
DISPLAY INVISIBLE (150 125);
FORCEPROP 2 LAST SEC_TYPE 0603V
J 0
(150 125);
DISPLAY 1.021277 (150 125);
PAINT ORANGE (150 125);
DISPLAY INVISIBLE (150 125);
FORCEPROP 2 LAST CDS_SEC 1
J 0
(150 75);
PAINT ORANGE (150 75);
DISPLAY INVISIBLE (150 75);
FORCEPROP 2 LAST CDS_LOCATION C3A2
J 0
(150 25);
DISPLAY 0.617021 (150 25);
PAINT AQUA (150 25);
DISPLAY INVISIBLE (150 25);
FORCEPROP 1 LAST PATH I216
J 0
(150 75);
DISPLAY 0.978723 (150 75);
PAINT WHITE (150 75);
DISPLAY INVISIBLE (150 75);
FORCEPROP 0 LAST ROOM PVDDQ_KLM
J 0
(150 125);
DISPLAY 1.021277 (150 125);
PAINT ORANGE (150 125);
DISPLAY INVISIBLE (150 125);
FORCEADD CAP_A..1
(-225 -75);
FORCEPROP 1 LAST PACK_TYPE 0603V
J 0
(-175 -275);
DISPLAY 0.617021 (-175 -275);
PAINT SKYBLUE (-175 -275);
FORCEPROP 1 LASTPIN (-225 -175) $PN 2
J 0
(-215 -195);
DISPLAY 0.617021 (-215 -195);
PAINT ORANGE (-215 -195);
FORCEPROP 1 LAST MATERIAL X6S
J 0
(-175 -175);
DISPLAY 0.617021 (-175 -175);
PAINT SKYBLUE (-175 -175);
FORCEPROP 1 LAST VOLTAGE 4V
J 0
(-175 -75);
DISPLAY 0.617021 (-175 -75);
PAINT SKYBLUE (-175 -75);
FORCEPROP 1 LAST TOLERANCE 20%
J 0
(-175 -125);
DISPLAY 0.617021 (-175 -125);
PAINT SKYBLUE (-175 -125);
FORCEPROP 1 LAST VALUE 22.0UF
J 0
(-175 -25);
DISPLAY 0.617021 (-175 -25);
PAINT SKYBLUE (-175 -25);
FORCEPROP 1 LASTPIN (-225 25) $PN 1
J 0
(-215 5);
DISPLAY 0.617021 (-215 5);
PAINT ORANGE (-215 5);
FORCEPROP 1 LAST LOCATION C3A1
J 0
(-175 25);
DISPLAY 0.617021 (-175 25);
PAINT AQUA (-175 25);
FORCEPROP 1 LAST PART_NUMBER E15431-004
J 0
(-175 -225);
DISPLAY 0.617021 (-175 -225);
PAINT BLUE (-175 -225);
FORCEPROP 2 LAST CDS_LIB dev_discrete
J 0
(-225 -75);
PAINT ORANGE (-225 -75);
DISPLAY INVISIBLE (-225 -75);
FORCEPROP 1 LAST PATH I217
J 0
(-175 75);
DISPLAY 0.978723 (-175 75);
PAINT WHITE (-175 75);
DISPLAY INVISIBLE (-175 75);
FORCEPROP 2 LAST CDS_SEC 1
J 0
(-175 75);
PAINT ORANGE (-175 75);
DISPLAY INVISIBLE (-175 75);
FORCEPROP 2 LAST CDS_LOCATION C3A1
J 0
(-175 25);
DISPLAY 0.617021 (-175 25);
PAINT AQUA (-175 25);
DISPLAY INVISIBLE (-175 25);
FORCEPROP 0 LAST ROOM PVDDQ_KLM
J 0
(-175 125);
DISPLAY 1.021277 (-175 125);
PAINT ORANGE (-175 125);
DISPLAY INVISIBLE (-175 125);
FORCEPROP 2 LAST SEC 1
J 0
(-175 125);
DISPLAY 0.680851 (-175 125);
PAINT MONO (-175 125);
DISPLAY INVISIBLE (-175 125);
FORCEPROP 2 LAST SEC_TYPE 0603V
J 0
(-175 125);
DISPLAY 1.021277 (-175 125);
PAINT ORANGE (-175 125);
DISPLAY INVISIBLE (-175 125);
FORCEADD CAP_A..1
(-500 -75);
FORCEPROP 1 LASTPIN (-500 -175) $PN 2
J 0
(-490 -195);
DISPLAY 0.617021 (-490 -195);
PAINT ORANGE (-490 -195);
FORCEPROP 1 LAST MATERIAL X6S
J 0
(-450 -175);
DISPLAY 0.617021 (-450 -175);
PAINT SKYBLUE (-450 -175);
FORCEPROP 1 LAST VOLTAGE 4V
J 0
(-450 -75);
DISPLAY 0.617021 (-450 -75);
PAINT SKYBLUE (-450 -75);
FORCEPROP 1 LAST PACK_TYPE 0603V
J 0
(-450 -275);
DISPLAY 0.617021 (-450 -275);
PAINT SKYBLUE (-450 -275);
FORCEPROP 1 LAST TOLERANCE 20%
J 0
(-450 -125);
DISPLAY 0.617021 (-450 -125);
PAINT SKYBLUE (-450 -125);
FORCEPROP 1 LAST PART_NUMBER E15431-004
J 0
(-450 -225);
DISPLAY 0.617021 (-450 -225);
PAINT BLUE (-450 -225);
FORCEPROP 1 LAST VALUE 22.0UF
J 0
(-450 -25);
DISPLAY 0.617021 (-450 -25);
PAINT SKYBLUE (-450 -25);
FORCEPROP 1 LAST LOCATION C2A7
J 0
(-450 25);
DISPLAY 0.617021 (-450 25);
PAINT AQUA (-450 25);
FORCEPROP 1 LASTPIN (-500 25) $PN 1
J 0
(-490 5);
DISPLAY 0.617021 (-490 5);
PAINT ORANGE (-490 5);
FORCEPROP 2 LAST CDS_LIB dev_discrete
J 0
(-500 -75);
PAINT ORANGE (-500 -75);
DISPLAY INVISIBLE (-500 -75);
FORCEPROP 2 LAST CDS_LOCATION C2A7
J 0
(-450 25);
DISPLAY 0.617021 (-450 25);
PAINT AQUA (-450 25);
DISPLAY INVISIBLE (-450 25);
FORCEPROP 2 LAST CDS_SEC 1
J 0
(-450 75);
PAINT ORANGE (-450 75);
DISPLAY INVISIBLE (-450 75);
FORCEPROP 2 LAST SEC_TYPE 0603V
J 0
(-450 125);
DISPLAY 1.021277 (-450 125);
PAINT ORANGE (-450 125);
DISPLAY INVISIBLE (-450 125);
FORCEPROP 2 LAST SEC 1
J 0
(-450 125);
DISPLAY 0.680851 (-450 125);
PAINT MONO (-450 125);
DISPLAY INVISIBLE (-450 125);
FORCEPROP 1 LAST PATH I218
J 0
(-450 75);
DISPLAY 0.978723 (-450 75);
PAINT WHITE (-450 75);
DISPLAY INVISIBLE (-450 75);
FORCEPROP 0 LAST ROOM PVDDQ_KLM
J 0
(-450 125);
DISPLAY 1.021277 (-450 125);
PAINT ORANGE (-450 125);
DISPLAY INVISIBLE (-450 125);
FORCEADD CAP_A..1
(-800 -75);
FORCEPROP 1 LASTPIN (-800 -175) $PN 2
J 0
(-790 -195);
DISPLAY 0.617021 (-790 -195);
PAINT ORANGE (-790 -195);
FORCEPROP 1 LAST MATERIAL X6S
J 0
(-750 -175);
DISPLAY 0.617021 (-750 -175);
PAINT SKYBLUE (-750 -175);
FORCEPROP 1 LAST VOLTAGE 4V
J 0
(-750 -75);
DISPLAY 0.617021 (-750 -75);
PAINT SKYBLUE (-750 -75);
FORCEPROP 1 LAST PACK_TYPE 0603V
J 0
(-750 -275);
DISPLAY 0.617021 (-750 -275);
PAINT SKYBLUE (-750 -275);
FORCEPROP 1 LAST TOLERANCE 20%
J 0
(-750 -125);
DISPLAY 0.617021 (-750 -125);
PAINT SKYBLUE (-750 -125);
FORCEPROP 1 LAST PART_NUMBER E15431-004
J 0
(-750 -225);
DISPLAY 0.617021 (-750 -225);
PAINT BLUE (-750 -225);
FORCEPROP 1 LASTPIN (-800 25) $PN 1
J 0
(-790 5);
DISPLAY 0.617021 (-790 5);
PAINT ORANGE (-790 5);
FORCEPROP 1 LAST LOCATION C2A6
J 0
(-750 25);
DISPLAY 0.617021 (-750 25);
PAINT AQUA (-750 25);
FORCEPROP 1 LAST VALUE 22.0UF
J 0
(-750 -25);
DISPLAY 0.617021 (-750 -25);
PAINT SKYBLUE (-750 -25);
FORCEPROP 2 LAST CDS_LIB dev_discrete
J 0
(-800 -75);
PAINT ORANGE (-800 -75);
DISPLAY INVISIBLE (-800 -75);
FORCEPROP 0 LAST ROOM PVDDQ_KLM
J 0
(-750 125);
DISPLAY 1.021277 (-750 125);
PAINT ORANGE (-750 125);
DISPLAY INVISIBLE (-750 125);
FORCEPROP 1 LAST PATH I219
J 0
(-750 75);
DISPLAY 0.978723 (-750 75);
PAINT WHITE (-750 75);
DISPLAY INVISIBLE (-750 75);
FORCEPROP 2 LAST SEC 1
J 0
(-750 125);
DISPLAY 0.680851 (-750 125);
PAINT MONO (-750 125);
DISPLAY INVISIBLE (-750 125);
FORCEPROP 2 LAST SEC_TYPE 0603V
J 0
(-750 125);
DISPLAY 1.021277 (-750 125);
PAINT ORANGE (-750 125);
DISPLAY INVISIBLE (-750 125);
FORCEPROP 2 LAST CDS_SEC 1
J 0
(-750 75);
PAINT ORANGE (-750 75);
DISPLAY INVISIBLE (-750 75);
FORCEPROP 2 LAST CDS_LOCATION C2A6
J 0
(-750 25);
DISPLAY 0.617021 (-750 25);
PAINT AQUA (-750 25);
DISPLAY INVISIBLE (-750 25);
FORCEADD CAP_A..1
(-1100 -75);
FORCEPROP 1 LASTPIN (-1100 -175) $PN 2
J 0
(-1090 -195);
DISPLAY 0.617021 (-1090 -195);
PAINT ORANGE (-1090 -195);
FORCEPROP 1 LAST PART_NUMBER E15431-004
J 0
(-1050 -225);
DISPLAY 0.617021 (-1050 -225);
PAINT BLUE (-1050 -225);
FORCEPROP 1 LAST TOLERANCE 20%
J 0
(-1050 -125);
DISPLAY 0.617021 (-1050 -125);
PAINT SKYBLUE (-1050 -125);
FORCEPROP 1 LAST PACK_TYPE 0603V
J 0
(-1050 -275);
DISPLAY 0.617021 (-1050 -275);
PAINT SKYBLUE (-1050 -275);
FORCEPROP 1 LAST VOLTAGE 4V
J 0
(-1050 -75);
DISPLAY 0.617021 (-1050 -75);
PAINT SKYBLUE (-1050 -75);
FORCEPROP 1 LAST MATERIAL X6S
J 0
(-1050 -175);
DISPLAY 0.617021 (-1050 -175);
PAINT SKYBLUE (-1050 -175);
FORCEPROP 1 LASTPIN (-1100 25) $PN 1
J 0
(-1090 5);
DISPLAY 0.617021 (-1090 5);
PAINT ORANGE (-1090 5);
FORCEPROP 1 LAST LOCATION C2A14
J 0
(-1050 25);
DISPLAY 0.617021 (-1050 25);
PAINT AQUA (-1050 25);
FORCEPROP 1 LAST VALUE 22.0UF
J 0
(-1050 -25);
DISPLAY 0.617021 (-1050 -25);
PAINT SKYBLUE (-1050 -25);
FORCEPROP 2 LAST CDS_LIB dev_discrete
J 0
(-1100 -75);
PAINT ORANGE (-1100 -75);
DISPLAY INVISIBLE (-1100 -75);
FORCEPROP 1 LAST PATH I220
J 0
(-1050 75);
DISPLAY 0.978723 (-1050 75);
PAINT WHITE (-1050 75);
DISPLAY INVISIBLE (-1050 75);
FORCEPROP 2 LAST CDS_SEC 1
J 0
(-1050 75);
PAINT ORANGE (-1050 75);
DISPLAY INVISIBLE (-1050 75);
FORCEPROP 2 LAST CDS_LOCATION C2A14
J 0
(-1050 25);
DISPLAY 0.617021 (-1050 25);
PAINT AQUA (-1050 25);
DISPLAY INVISIBLE (-1050 25);
FORCEPROP 0 LAST ROOM PVDDQ_KLM
J 0
(-1050 125);
DISPLAY 1.021277 (-1050 125);
PAINT ORANGE (-1050 125);
DISPLAY INVISIBLE (-1050 125);
FORCEPROP 2 LAST SEC 1
J 0
(-1050 125);
DISPLAY 0.680851 (-1050 125);
PAINT MONO (-1050 125);
DISPLAY INVISIBLE (-1050 125);
FORCEPROP 2 LAST SEC_TYPE 0603V
J 0
(-1050 125);
DISPLAY 1.021277 (-1050 125);
PAINT ORANGE (-1050 125);
DISPLAY INVISIBLE (-1050 125);
FORCEADD CAP_A..1
(-1375 -75);
FORCEPROP 1 LASTPIN (-1375 -175) $PN 2
J 0
(-1365 -195);
DISPLAY 0.617021 (-1365 -195);
PAINT ORANGE (-1365 -195);
FORCEPROP 1 LAST VOLTAGE 4V
J 0
(-1325 -75);
DISPLAY 0.617021 (-1325 -75);
PAINT SKYBLUE (-1325 -75);
FORCEPROP 1 LAST TOLERANCE 20%
J 0
(-1325 -125);
DISPLAY 0.617021 (-1325 -125);
PAINT SKYBLUE (-1325 -125);
FORCEPROP 1 LAST PART_NUMBER E15431-004
J 0
(-1325 -225);
DISPLAY 0.617021 (-1325 -225);
PAINT BLUE (-1325 -225);
FORCEPROP 1 LAST MATERIAL X6S
J 0
(-1325 -175);
DISPLAY 0.617021 (-1325 -175);
PAINT SKYBLUE (-1325 -175);
FORCEPROP 1 LASTPIN (-1375 25) $PN 1
J 0
(-1365 5);
DISPLAY 0.617021 (-1365 5);
PAINT ORANGE (-1365 5);
FORCEPROP 1 LAST LOCATION C2A15
J 0
(-1325 25);
DISPLAY 0.617021 (-1325 25);
PAINT AQUA (-1325 25);
FORCEPROP 1 LAST VALUE 22.0UF
J 0
(-1325 -25);
DISPLAY 0.617021 (-1325 -25);
PAINT SKYBLUE (-1325 -25);
FORCEPROP 1 LAST PACK_TYPE 0603V
J 0
(-1325 -275);
DISPLAY 0.617021 (-1325 -275);
PAINT SKYBLUE (-1325 -275);
FORCEPROP 2 LAST CDS_LIB dev_discrete
J 0
(-1375 -75);
PAINT ORANGE (-1375 -75);
DISPLAY INVISIBLE (-1375 -75);
FORCEPROP 1 LAST PATH I221
J 0
(-1325 75);
DISPLAY 0.978723 (-1325 75);
PAINT WHITE (-1325 75);
DISPLAY INVISIBLE (-1325 75);
FORCEPROP 2 LAST CDS_SEC 1
J 0
(-1325 75);
PAINT ORANGE (-1325 75);
DISPLAY INVISIBLE (-1325 75);
FORCEPROP 2 LAST CDS_LOCATION C2A15
J 0
(-1325 25);
DISPLAY 0.617021 (-1325 25);
PAINT AQUA (-1325 25);
DISPLAY INVISIBLE (-1325 25);
FORCEPROP 0 LAST ROOM PVDDQ_KLM
J 0
(-1325 125);
DISPLAY 1.021277 (-1325 125);
PAINT ORANGE (-1325 125);
DISPLAY INVISIBLE (-1325 125);
FORCEPROP 2 LAST SEC 1
J 0
(-1325 125);
DISPLAY 0.680851 (-1325 125);
PAINT MONO (-1325 125);
DISPLAY INVISIBLE (-1325 125);
FORCEPROP 2 LAST SEC_TYPE 0603V
J 0
(-1325 125);
DISPLAY 1.021277 (-1325 125);
PAINT ORANGE (-1325 125);
DISPLAY INVISIBLE (-1325 125);
FORCEADD CAP_A..1
(-1650 -75);
FORCEPROP 1 LASTPIN (-1650 -175) $PN 2
J 0
(-1640 -195);
DISPLAY 0.617021 (-1640 -195);
PAINT ORANGE (-1640 -195);
FORCEPROP 1 LAST VOLTAGE 4V
J 0
(-1600 -75);
DISPLAY 0.617021 (-1600 -75);
PAINT SKYBLUE (-1600 -75);
FORCEPROP 1 LAST PACK_TYPE 0603V
J 0
(-1600 -275);
DISPLAY 0.617021 (-1600 -275);
PAINT SKYBLUE (-1600 -275);
FORCEPROP 1 LASTPIN (-1650 25) $PN 1
J 0
(-1640 5);
DISPLAY 0.617021 (-1640 5);
PAINT ORANGE (-1640 5);
FORCEPROP 1 LAST LOCATION C3A5
J 0
(-1600 25);
DISPLAY 0.617021 (-1600 25);
PAINT AQUA (-1600 25);
FORCEPROP 1 LAST VALUE 22.0UF
J 0
(-1600 -25);
DISPLAY 0.617021 (-1600 -25);
PAINT SKYBLUE (-1600 -25);
FORCEPROP 1 LAST TOLERANCE 20%
J 0
(-1600 -125);
DISPLAY 0.617021 (-1600 -125);
PAINT SKYBLUE (-1600 -125);
FORCEPROP 1 LAST MATERIAL X6S
J 0
(-1600 -175);
DISPLAY 0.617021 (-1600 -175);
PAINT SKYBLUE (-1600 -175);
FORCEPROP 1 LAST PART_NUMBER E15431-004
J 0
(-1600 -225);
DISPLAY 0.617021 (-1600 -225);
PAINT BLUE (-1600 -225);
FORCEPROP 2 LAST CDS_LIB dev_discrete
J 0
(-1650 -75);
PAINT ORANGE (-1650 -75);
DISPLAY INVISIBLE (-1650 -75);
FORCEPROP 1 LAST PATH I222
J 0
(-1600 75);
DISPLAY 0.978723 (-1600 75);
PAINT WHITE (-1600 75);
DISPLAY INVISIBLE (-1600 75);
FORCEPROP 2 LAST CDS_SEC 1
J 0
(-1600 75);
PAINT ORANGE (-1600 75);
DISPLAY INVISIBLE (-1600 75);
FORCEPROP 2 LAST CDS_LOCATION C3A5
J 0
(-1600 25);
DISPLAY 0.617021 (-1600 25);
PAINT AQUA (-1600 25);
DISPLAY INVISIBLE (-1600 25);
FORCEPROP 0 LAST ROOM PVDDQ_KLM
J 0
(-1600 125);
DISPLAY 1.021277 (-1600 125);
PAINT ORANGE (-1600 125);
DISPLAY INVISIBLE (-1600 125);
FORCEPROP 2 LAST SEC 1
J 0
(-1600 125);
DISPLAY 0.680851 (-1600 125);
PAINT MONO (-1600 125);
DISPLAY INVISIBLE (-1600 125);
FORCEPROP 2 LAST SEC_TYPE 0603V
J 0
(-1600 125);
DISPLAY 1.021277 (-1600 125);
PAINT ORANGE (-1600 125);
DISPLAY INVISIBLE (-1600 125);
FORCEADD CAP_A..1
(-1950 -75);
FORCEPROP 1 LASTPIN (-1950 -175) $PN 2
J 0
(-1940 -195);
DISPLAY 0.617021 (-1940 -195);
PAINT ORANGE (-1940 -195);
FORCEPROP 1 LAST VOLTAGE 4V
J 0
(-1900 -75);
DISPLAY 0.617021 (-1900 -75);
PAINT SKYBLUE (-1900 -75);
FORCEPROP 1 LAST TOLERANCE 20%
J 0
(-1900 -125);
DISPLAY 0.617021 (-1900 -125);
PAINT SKYBLUE (-1900 -125);
FORCEPROP 1 LAST PART_NUMBER E15431-004
J 0
(-1900 -225);
DISPLAY 0.617021 (-1900 -225);
PAINT BLUE (-1900 -225);
FORCEPROP 1 LAST VALUE 22.0UF
J 0
(-1900 -25);
DISPLAY 0.617021 (-1900 -25);
PAINT SKYBLUE (-1900 -25);
FORCEPROP 1 LASTPIN (-1950 25) $PN 1
J 0
(-1940 5);
DISPLAY 0.617021 (-1940 5);
PAINT ORANGE (-1940 5);
FORCEPROP 1 LAST LOCATION C3A6
J 0
(-1900 25);
DISPLAY 0.617021 (-1900 25);
PAINT AQUA (-1900 25);
FORCEPROP 1 LAST MATERIAL X6S
J 0
(-1900 -175);
DISPLAY 0.617021 (-1900 -175);
PAINT SKYBLUE (-1900 -175);
FORCEPROP 1 LAST PACK_TYPE 0603V
J 0
(-1900 -275);
DISPLAY 0.617021 (-1900 -275);
PAINT SKYBLUE (-1900 -275);
FORCEPROP 2 LAST CDS_LIB dev_discrete
J 0
(-1950 -75);
PAINT ORANGE (-1950 -75);
DISPLAY INVISIBLE (-1950 -75);
FORCEPROP 2 LAST SEC 1
J 0
(-1900 125);
DISPLAY 0.680851 (-1900 125);
PAINT MONO (-1900 125);
DISPLAY INVISIBLE (-1900 125);
FORCEPROP 2 LAST SEC_TYPE 0603V
J 0
(-1900 125);
DISPLAY 1.021277 (-1900 125);
PAINT ORANGE (-1900 125);
DISPLAY INVISIBLE (-1900 125);
FORCEPROP 2 LAST CDS_SEC 1
J 0
(-1900 75);
PAINT ORANGE (-1900 75);
DISPLAY INVISIBLE (-1900 75);
FORCEPROP 2 LAST CDS_LOCATION C3A6
J 0
(-1900 25);
DISPLAY 0.617021 (-1900 25);
PAINT AQUA (-1900 25);
DISPLAY INVISIBLE (-1900 25);
FORCEPROP 1 LAST PATH I223
J 0
(-1900 75);
DISPLAY 0.978723 (-1900 75);
PAINT WHITE (-1900 75);
DISPLAY INVISIBLE (-1900 75);
FORCEPROP 0 LAST ROOM PVDDQ_KLM
J 0
(-1900 125);
DISPLAY 1.021277 (-1900 125);
PAINT ORANGE (-1900 125);
DISPLAY INVISIBLE (-1900 125);
FORCEADD PVDDQ_KLM..1
(-2250 175);
FORCEPROP 3 LASTPIN (-2250 125) SIG_NAME PVDDQ_KLM\g
J 0
(-2240 135);
DISPLAY 0.659574 (-2240 135);
PAINT MONO (-2240 135);
DISPLAY INVISIBLE (-2240 135);
FORCEPROP 2 LAST CDS_LIB mstr_symbols
J 0
(-2250 175);
PAINT ORANGE (-2250 175);
DISPLAY INVISIBLE (-2250 175);
FORCEPROP 1 LAST VOLTAGE 1.2V
J 0
(-2295 132);
DISPLAY 0.340426 (-2295 132);
PAINT SKYBLUE (-2295 132);
DISPLAY INVISIBLE (-2295 132);
FORCEPROP 1 LAST PATH I224
J 0
(-2200 200);
DISPLAY 0.872340 (-2200 200);
PAINT AQUA (-2200 200);
DISPLAY INVISIBLE (-2200 200);
FORCEPROP 2 LAST BOM_COST VDDQ_KLM_PWR_VR
J 0
(-2250 275);
DISPLAY 1.446809 (-2250 275);
PAINT MONO (-2250 275);
DISPLAY INVISIBLE (-2250 275);
FORCEPROP 2 LAST ROOM VDDQ_KLM_PWR_VR
J 0
(-2250 275);
DISPLAY 1.936170 (-2250 275);
PAINT ORANGE (-2250 275);
DISPLAY INVISIBLE (-2250 275);
FORCEPROP 1 LAST BODY_TYPE PLUMBING
J 0
(-2295 132);
DISPLAY 0.340426 (-2295 132);
PAINT GREEN (-2295 132);
DISPLAY INVISIBLE (-2295 132);
FORCEPROP 1 LAST HDL_POWER PVDDQ_KLM
J 1
(-2250 225);
DISPLAY 0.872340 (-2250 225);
PAINT GREEN (-2250 225);
DISPLAY INVISIBLE (-2250 225);
FORCEADD CAP_A..1
(-2250 -75);
FORCEPROP 1 LASTPIN (-2250 25) $PN 1
J 0
(-2240 5);
DISPLAY 0.617021 (-2240 5);
PAINT ORANGE (-2240 5);
FORCEPROP 1 LASTPIN (-2250 -175) $PN 2
J 0
(-2240 -195);
DISPLAY 0.617021 (-2240 -195);
PAINT ORANGE (-2240 -195);
FORCEPROP 1 LAST LOCATION C7L5
J 0
(-2200 25);
DISPLAY 0.617021 (-2200 25);
PAINT AQUA (-2200 25);
FORCEPROP 1 LAST VALUE 22.0UF
J 0
(-2200 -25);
DISPLAY 0.617021 (-2200 -25);
PAINT SKYBLUE (-2200 -25);
FORCEPROP 1 LAST PART_NUMBER E15431-004
J 0
(-2200 -225);
DISPLAY 0.617021 (-2200 -225);
PAINT BLUE (-2200 -225);
FORCEPROP 1 LAST TOLERANCE 20%
J 0
(-2200 -125);
DISPLAY 0.617021 (-2200 -125);
PAINT SKYBLUE (-2200 -125);
FORCEPROP 1 LAST VOLTAGE 4V
J 0
(-2200 -75);
DISPLAY 0.617021 (-2200 -75);
PAINT SKYBLUE (-2200 -75);
FORCEPROP 1 LAST MATERIAL X6S
J 0
(-2200 -175);
DISPLAY 0.617021 (-2200 -175);
PAINT SKYBLUE (-2200 -175);
FORCEPROP 1 LAST PACK_TYPE 0603V
J 0
(-2200 -275);
DISPLAY 0.617021 (-2200 -275);
PAINT SKYBLUE (-2200 -275);
FORCEPROP 2 LAST CDS_LOCATION C7L5
J 0
(-2200 25);
DISPLAY 0.617021 (-2200 25);
PAINT AQUA (-2200 25);
DISPLAY INVISIBLE (-2200 25);
FORCEPROP 2 LAST CDS_SEC 1
J 0
(-2200 75);
PAINT ORANGE (-2200 75);
DISPLAY INVISIBLE (-2200 75);
FORCEPROP 2 LAST CDS_LIB dev_discrete
J 0
(-2250 -75);
PAINT ORANGE (-2250 -75);
DISPLAY INVISIBLE (-2250 -75);
FORCEPROP 2 LAST SEC 1
J 0
(-2200 125);
DISPLAY 0.680851 (-2200 125);
PAINT MONO (-2200 125);
DISPLAY INVISIBLE (-2200 125);
FORCEPROP 2 LAST SEC_TYPE 0603V
J 0
(-2200 125);
DISPLAY 1.021277 (-2200 125);
PAINT ORANGE (-2200 125);
DISPLAY INVISIBLE (-2200 125);
FORCEPROP 1 LAST PATH I225
J 0
(-2200 75);
DISPLAY 0.978723 (-2200 75);
PAINT WHITE (-2200 75);
DISPLAY INVISIBLE (-2200 75);
FORCEPROP 0 LAST ROOM PVDDQ_KLM
J 0
(-2200 125);
DISPLAY 1.021277 (-2200 125);
PAINT ORANGE (-2200 125);
DISPLAY INVISIBLE (-2200 125);
FORCEADD GND..1
(-2250 -350);
FORCEPROP 3 LASTPIN (-2250 -300) SIG_NAME GND\g
J 0
(-2240 -290);
DISPLAY 0.659574 (-2240 -290);
PAINT MONO (-2240 -290);
DISPLAY INVISIBLE (-2240 -290);
FORCEPROP 2 LAST BOM_COST PROC_VRD_VCCIN_CPU0
J 0
(-2625 -275);
DISPLAY 1.446809 (-2625 -275);
PAINT MONO (-2625 -275);
DISPLAY INVISIBLE (-2625 -275);
FORCEPROP 2 LAST ROOM VDDQ_ABC_PWR_VR
J 0
(-2800 -275);
DISPLAY 1.936170 (-2800 -275);
PAINT ORANGE (-2800 -275);
DISPLAY INVISIBLE (-2800 -275);
FORCEPROP 2 LAST CDS_LIB mstr_symbols
J 0
(-2250 -350);
PAINT ORANGE (-2250 -350);
DISPLAY INVISIBLE (-2250 -350);
FORCEPROP 1 LAST VOLTAGE 0
J 0
(-2250 -350);
PAINT SKYBLUE (-2250 -350);
DISPLAY INVISIBLE (-2250 -350);
FORCEPROP 1 LAST PATH I226
J 0
(-2175 -350);
DISPLAY 0.872340 (-2175 -350);
PAINT AQUA (-2175 -350);
DISPLAY INVISIBLE (-2175 -350);
FORCEPROP 1 LAST SIZE 1B
J 0
(-2175 -400);
DISPLAY 1.723404 (-2175 -400);
PAINT GREEN (-2175 -400);
DISPLAY INVISIBLE (-2175 -400);
FORCEPROP 1 LAST BODY_TYPE PLUMBING
J 0
(-2295 -393);
DISPLAY 0.340426 (-2295 -393);
PAINT GREEN (-2295 -393);
DISPLAY INVISIBLE (-2295 -393);
FORCEPROP 1 LAST HDL_POWER GND
J 0
(-2250 -200);
DISPLAY 1.723404 (-2250 -200);
PAINT GREEN (-2250 -200);
DISPLAY INVISIBLE (-2250 -200);
FORCEADD CAP_A..1
(2150 -775);
FORCEPROP 1 LAST TOLERANCE 20%
J 0
(2200 -825);
DISPLAY 0.617021 (2200 -825);
PAINT SKYBLUE (2200 -825);
FORCEPROP 1 LAST MATERIAL X6S
J 0
(2200 -875);
DISPLAY 0.617021 (2200 -875);
PAINT SKYBLUE (2200 -875);
FORCEPROP 1 LASTPIN (2150 -875) $PN 2
J 0
(2160 -895);
DISPLAY 0.617021 (2160 -895);
PAINT ORANGE (2160 -895);
FORCEPROP 1 LAST VOLTAGE 4V
J 0
(2200 -775);
DISPLAY 0.617021 (2200 -775);
PAINT SKYBLUE (2200 -775);
FORCEPROP 1 LASTPIN (2150 -675) $PN 1
J 0
(2160 -695);
DISPLAY 0.617021 (2160 -695);
PAINT ORANGE (2160 -695);
FORCEPROP 1 LAST PACK_TYPE 0603V
J 0
(2200 -975);
DISPLAY 0.617021 (2200 -975);
PAINT SKYBLUE (2200 -975);
FORCEPROP 1 LAST VALUE 22.0UF
J 0
(2200 -725);
DISPLAY 0.617021 (2200 -725);
PAINT SKYBLUE (2200 -725);
FORCEPROP 1 LAST LOCATION C8M3
J 0
(2200 -675);
DISPLAY 0.617021 (2200 -675);
PAINT AQUA (2200 -675);
FORCEPROP 1 LAST PART_NUMBER E15431-004
J 0
(2200 -925);
DISPLAY 0.617021 (2200 -925);
PAINT BLUE (2200 -925);
FORCEPROP 2 LAST CDS_LIB dev_discrete
J 0
(2150 -775);
PAINT ORANGE (2150 -775);
DISPLAY INVISIBLE (2150 -775);
FORCEPROP 2 LAST CDS_SEC 1
J 0
(2200 -625);
PAINT ORANGE (2200 -625);
DISPLAY INVISIBLE (2200 -625);
FORCEPROP 2 LAST CDS_LOCATION C8M3
J 0
(2200 -675);
DISPLAY 0.617021 (2200 -675);
PAINT AQUA (2200 -675);
DISPLAY INVISIBLE (2200 -675);
FORCEPROP 2 LAST SEC_TYPE 0603V
J 0
(2200 -575);
DISPLAY 1.021277 (2200 -575);
PAINT ORANGE (2200 -575);
DISPLAY INVISIBLE (2200 -575);
FORCEPROP 2 LAST SEC 1
J 0
(2200 -625);
DISPLAY 0.680851 (2200 -625);
PAINT MONO (2200 -625);
DISPLAY INVISIBLE (2200 -625);
FORCEPROP 1 LAST PATH I227
J 0
(2200 -625);
DISPLAY 0.978723 (2200 -625);
PAINT WHITE (2200 -625);
DISPLAY INVISIBLE (2200 -625);
FORCEPROP 0 LAST ROOM PVDDQ_KLM
J 0
(2200 -575);
DISPLAY 1.021277 (2200 -575);
PAINT ORANGE (2200 -575);
DISPLAY INVISIBLE (2200 -575);
FORCEADD CAP_A..1
(1875 -775);
FORCEPROP 1 LASTPIN (1875 -875) $PN 2
J 0
(1885 -895);
DISPLAY 0.617021 (1885 -895);
PAINT ORANGE (1885 -895);
FORCEPROP 1 LAST MATERIAL X6S
J 0
(1925 -875);
DISPLAY 0.617021 (1925 -875);
PAINT SKYBLUE (1925 -875);
FORCEPROP 1 LAST TOLERANCE 20%
J 0
(1925 -825);
DISPLAY 0.617021 (1925 -825);
PAINT SKYBLUE (1925 -825);
FORCEPROP 1 LAST VOLTAGE 4V
J 0
(1925 -775);
DISPLAY 0.617021 (1925 -775);
PAINT SKYBLUE (1925 -775);
FORCEPROP 1 LASTPIN (1875 -675) $PN 1
J 0
(1885 -695);
DISPLAY 0.617021 (1885 -695);
PAINT ORANGE (1885 -695);
FORCEPROP 1 LAST LOCATION C8M5
J 0
(1925 -675);
DISPLAY 0.617021 (1925 -675);
PAINT AQUA (1925 -675);
FORCEPROP 1 LAST PART_NUMBER E15431-004
J 0
(1925 -925);
DISPLAY 0.617021 (1925 -925);
PAINT BLUE (1925 -925);
FORCEPROP 1 LAST VALUE 22.0UF
J 0
(1925 -725);
DISPLAY 0.617021 (1925 -725);
PAINT SKYBLUE (1925 -725);
FORCEPROP 1 LAST PACK_TYPE 0603V
J 0
(1925 -975);
DISPLAY 0.617021 (1925 -975);
PAINT SKYBLUE (1925 -975);
FORCEPROP 2 LAST CDS_LIB dev_discrete
J 0
(1875 -775);
PAINT ORANGE (1875 -775);
DISPLAY INVISIBLE (1875 -775);
FORCEPROP 0 LAST ROOM PVDDQ_KLM
J 0
(1925 -575);
DISPLAY 1.021277 (1925 -575);
PAINT ORANGE (1925 -575);
DISPLAY INVISIBLE (1925 -575);
FORCEPROP 1 LAST PATH I228
J 0
(1925 -625);
DISPLAY 0.978723 (1925 -625);
PAINT WHITE (1925 -625);
DISPLAY INVISIBLE (1925 -625);
FORCEPROP 2 LAST SEC 1
J 0
(1925 -625);
DISPLAY 0.680851 (1925 -625);
PAINT MONO (1925 -625);
DISPLAY INVISIBLE (1925 -625);
FORCEPROP 2 LAST SEC_TYPE 0603V
J 0
(1925 -575);
DISPLAY 1.021277 (1925 -575);
PAINT ORANGE (1925 -575);
DISPLAY INVISIBLE (1925 -575);
FORCEPROP 2 LAST CDS_SEC 1
J 0
(1925 -625);
PAINT ORANGE (1925 -625);
DISPLAY INVISIBLE (1925 -625);
FORCEPROP 2 LAST CDS_LOCATION C8M5
J 0
(1925 -675);
DISPLAY 0.617021 (1925 -675);
PAINT AQUA (1925 -675);
DISPLAY INVISIBLE (1925 -675);
FORCEADD CAP_A..1
(1575 -775);
FORCEPROP 1 LASTPIN (1575 -875) $PN 2
J 0
(1585 -895);
DISPLAY 0.617021 (1585 -895);
PAINT ORANGE (1585 -895);
FORCEPROP 1 LAST TOLERANCE 20%
J 0
(1625 -825);
DISPLAY 0.617021 (1625 -825);
PAINT SKYBLUE (1625 -825);
FORCEPROP 1 LAST PACK_TYPE 0603V
J 0
(1625 -975);
DISPLAY 0.617021 (1625 -975);
PAINT SKYBLUE (1625 -975);
FORCEPROP 1 LAST MATERIAL X6S
J 0
(1625 -875);
DISPLAY 0.617021 (1625 -875);
PAINT SKYBLUE (1625 -875);
FORCEPROP 1 LAST VOLTAGE 4V
J 0
(1625 -775);
DISPLAY 0.617021 (1625 -775);
PAINT SKYBLUE (1625 -775);
FORCEPROP 1 LASTPIN (1575 -675) $PN 1
J 0
(1585 -695);
DISPLAY 0.617021 (1585 -695);
PAINT ORANGE (1585 -695);
FORCEPROP 1 LAST LOCATION C8L10
J 0
(1625 -675);
DISPLAY 0.617021 (1625 -675);
PAINT AQUA (1625 -675);
FORCEPROP 1 LAST PART_NUMBER E15431-004
J 0
(1625 -925);
DISPLAY 0.617021 (1625 -925);
PAINT BLUE (1625 -925);
FORCEPROP 1 LAST VALUE 22.0UF
J 0
(1625 -725);
DISPLAY 0.617021 (1625 -725);
PAINT SKYBLUE (1625 -725);
FORCEPROP 2 LAST CDS_LIB dev_discrete
J 0
(1575 -775);
PAINT ORANGE (1575 -775);
DISPLAY INVISIBLE (1575 -775);
FORCEPROP 2 LAST CDS_LOCATION C8L10
J 0
(1625 -675);
DISPLAY 0.617021 (1625 -675);
PAINT AQUA (1625 -675);
DISPLAY INVISIBLE (1625 -675);
FORCEPROP 2 LAST CDS_SEC 1
J 0
(1625 -625);
PAINT ORANGE (1625 -625);
DISPLAY INVISIBLE (1625 -625);
FORCEPROP 2 LAST SEC_TYPE 0603V
J 0
(1625 -575);
DISPLAY 1.021277 (1625 -575);
PAINT ORANGE (1625 -575);
DISPLAY INVISIBLE (1625 -575);
FORCEPROP 2 LAST SEC 1
J 0
(1625 -625);
DISPLAY 0.680851 (1625 -625);
PAINT MONO (1625 -625);
DISPLAY INVISIBLE (1625 -625);
FORCEPROP 1 LAST PATH I229
J 0
(1625 -625);
DISPLAY 0.978723 (1625 -625);
PAINT WHITE (1625 -625);
DISPLAY INVISIBLE (1625 -625);
FORCEPROP 0 LAST ROOM PVDDQ_KLM
J 0
(1625 -575);
DISPLAY 1.021277 (1625 -575);
PAINT ORANGE (1625 -575);
DISPLAY INVISIBLE (1625 -575);
FORCEADD CAP_A..1
(1275 -775);
FORCEPROP 1 LAST LOCATION C2A3
J 0
(1325 -675);
DISPLAY 0.617021 (1325 -675);
PAINT AQUA (1325 -675);
FORCEPROP 1 LAST VALUE 22.0UF
J 0
(1325 -725);
DISPLAY 0.617021 (1325 -725);
PAINT SKYBLUE (1325 -725);
FORCEPROP 1 LAST TOLERANCE 20%
J 0
(1325 -825);
DISPLAY 0.617021 (1325 -825);
PAINT SKYBLUE (1325 -825);
FORCEPROP 1 LAST PACK_TYPE 0603V
J 0
(1325 -975);
DISPLAY 0.617021 (1325 -975);
PAINT SKYBLUE (1325 -975);
FORCEPROP 1 LAST VOLTAGE 4V
J 0
(1325 -775);
DISPLAY 0.617021 (1325 -775);
PAINT SKYBLUE (1325 -775);
FORCEPROP 1 LAST MATERIAL X6S
J 0
(1325 -875);
DISPLAY 0.617021 (1325 -875);
PAINT SKYBLUE (1325 -875);
FORCEPROP 1 LASTPIN (1275 -675) $PN 1
J 0
(1285 -695);
DISPLAY 0.617021 (1285 -695);
PAINT ORANGE (1285 -695);
FORCEPROP 1 LASTPIN (1275 -875) $PN 2
J 0
(1285 -895);
DISPLAY 0.617021 (1285 -895);
PAINT ORANGE (1285 -895);
FORCEPROP 1 LAST PART_NUMBER E15431-004
J 0
(1325 -925);
DISPLAY 0.617021 (1325 -925);
PAINT BLUE (1325 -925);
FORCEPROP 2 LAST CDS_LIB dev_discrete
J 0
(1275 -775);
PAINT ORANGE (1275 -775);
DISPLAY INVISIBLE (1275 -775);
FORCEPROP 2 LAST CDS_LOCATION C2A3
J 0
(1325 -675);
DISPLAY 0.617021 (1325 -675);
PAINT AQUA (1325 -675);
DISPLAY INVISIBLE (1325 -675);
FORCEPROP 2 LAST CDS_SEC 1
J 0
(1325 -625);
PAINT ORANGE (1325 -625);
DISPLAY INVISIBLE (1325 -625);
FORCEPROP 2 LAST SEC_TYPE 0603V
J 0
(1325 -575);
DISPLAY 1.021277 (1325 -575);
PAINT ORANGE (1325 -575);
DISPLAY INVISIBLE (1325 -575);
FORCEPROP 2 LAST SEC 1
J 0
(1325 -575);
DISPLAY 0.680851 (1325 -575);
PAINT MONO (1325 -575);
DISPLAY INVISIBLE (1325 -575);
FORCEPROP 1 LAST PATH I230
J 0
(1325 -625);
DISPLAY 0.978723 (1325 -625);
PAINT WHITE (1325 -625);
DISPLAY INVISIBLE (1325 -625);
FORCEPROP 0 LAST ROOM PVDDQ_KLM
J 0
(1325 -575);
DISPLAY 1.021277 (1325 -575);
PAINT ORANGE (1325 -575);
DISPLAY INVISIBLE (1325 -575);
FORCEADD CAP_A..1
(1000 -775);
FORCEPROP 1 LASTPIN (1000 -675) $PN 1
J 0
(1010 -695);
DISPLAY 0.617021 (1010 -695);
PAINT ORANGE (1010 -695);
FORCEPROP 1 LASTPIN (1000 -875) $PN 2
J 0
(1010 -895);
DISPLAY 0.617021 (1010 -895);
PAINT ORANGE (1010 -895);
FORCEPROP 1 LAST TOLERANCE 20%
J 0
(1050 -825);
DISPLAY 0.617021 (1050 -825);
PAINT SKYBLUE (1050 -825);
FORCEPROP 1 LAST PACK_TYPE 0603V
J 0
(1050 -975);
DISPLAY 0.617021 (1050 -975);
PAINT SKYBLUE (1050 -975);
FORCEPROP 1 LAST MATERIAL X6S
J 0
(1050 -875);
DISPLAY 0.617021 (1050 -875);
PAINT SKYBLUE (1050 -875);
FORCEPROP 1 LAST VOLTAGE 4V
J 0
(1050 -775);
DISPLAY 0.617021 (1050 -775);
PAINT SKYBLUE (1050 -775);
FORCEPROP 1 LAST VALUE 22.0UF
J 0
(1050 -725);
DISPLAY 0.617021 (1050 -725);
PAINT SKYBLUE (1050 -725);
FORCEPROP 1 LAST LOCATION C7M1
J 0
(1050 -675);
DISPLAY 0.617021 (1050 -675);
PAINT AQUA (1050 -675);
FORCEPROP 1 LAST PART_NUMBER E15431-004
J 0
(1050 -925);
DISPLAY 0.617021 (1050 -925);
PAINT BLUE (1050 -925);
FORCEPROP 2 LAST CDS_LIB dev_discrete
J 0
(1000 -775);
PAINT ORANGE (1000 -775);
DISPLAY INVISIBLE (1000 -775);
FORCEPROP 2 LAST SEC 1
J 0
(1050 -625);
DISPLAY 0.680851 (1050 -625);
PAINT MONO (1050 -625);
DISPLAY INVISIBLE (1050 -625);
FORCEPROP 2 LAST SEC_TYPE 0603V
J 0
(1050 -575);
DISPLAY 1.021277 (1050 -575);
PAINT ORANGE (1050 -575);
DISPLAY INVISIBLE (1050 -575);
FORCEPROP 1 LAST PATH I231
J 0
(1050 -625);
DISPLAY 0.978723 (1050 -625);
PAINT WHITE (1050 -625);
DISPLAY INVISIBLE (1050 -625);
FORCEPROP 0 LAST ROOM PVDDQ_KLM
J 0
(1050 -575);
DISPLAY 1.021277 (1050 -575);
PAINT ORANGE (1050 -575);
DISPLAY INVISIBLE (1050 -575);
FORCEPROP 2 LAST CDS_LOCATION C7M1
J 0
(1050 -675);
DISPLAY 0.617021 (1050 -675);
PAINT AQUA (1050 -675);
DISPLAY INVISIBLE (1050 -675);
FORCEPROP 2 LAST CDS_SEC 1
J 0
(1050 -625);
PAINT ORANGE (1050 -625);
DISPLAY INVISIBLE (1050 -625);
FORCEADD CAP_A..1
(725 -775);
FORCEPROP 1 LASTPIN (725 -875) $PN 2
J 0
(735 -895);
DISPLAY 0.617021 (735 -895);
PAINT ORANGE (735 -895);
FORCEPROP 1 LASTPIN (725 -675) $PN 1
J 0
(735 -695);
DISPLAY 0.617021 (735 -695);
PAINT ORANGE (735 -695);
FORCEPROP 1 LAST MATERIAL X6S
J 0
(775 -875);
DISPLAY 0.617021 (775 -875);
PAINT SKYBLUE (775 -875);
FORCEPROP 1 LAST PACK_TYPE 0603V
J 0
(775 -975);
DISPLAY 0.617021 (775 -975);
PAINT SKYBLUE (775 -975);
FORCEPROP 1 LAST TOLERANCE 20%
J 0
(775 -825);
DISPLAY 0.617021 (775 -825);
PAINT SKYBLUE (775 -825);
FORCEPROP 1 LAST VOLTAGE 4V
J 0
(775 -775);
DISPLAY 0.617021 (775 -775);
PAINT SKYBLUE (775 -775);
FORCEPROP 1 LAST LOCATION C7M2
J 0
(775 -675);
DISPLAY 0.617021 (775 -675);
PAINT AQUA (775 -675);
FORCEPROP 1 LAST VALUE 22.0UF
J 0
(775 -725);
DISPLAY 0.617021 (775 -725);
PAINT SKYBLUE (775 -725);
FORCEPROP 1 LAST PART_NUMBER E15431-004
J 0
(775 -925);
DISPLAY 0.617021 (775 -925);
PAINT BLUE (775 -925);
FORCEPROP 2 LAST CDS_LIB dev_discrete
J 0
(725 -775);
PAINT ORANGE (725 -775);
DISPLAY INVISIBLE (725 -775);
FORCEPROP 2 LAST CDS_SEC 1
J 0
(775 -625);
PAINT ORANGE (775 -625);
DISPLAY INVISIBLE (775 -625);
FORCEPROP 2 LAST CDS_LOCATION C7M2
J 0
(775 -675);
DISPLAY 0.617021 (775 -675);
PAINT AQUA (775 -675);
DISPLAY INVISIBLE (775 -675);
FORCEPROP 2 LAST SEC 1
J 0
(775 -625);
DISPLAY 0.680851 (775 -625);
PAINT MONO (775 -625);
DISPLAY INVISIBLE (775 -625);
FORCEPROP 2 LAST SEC_TYPE 0603V
J 0
(775 -575);
DISPLAY 1.021277 (775 -575);
PAINT ORANGE (775 -575);
DISPLAY INVISIBLE (775 -575);
FORCEPROP 0 LAST ROOM PVDDQ_KLM
J 0
(775 -575);
DISPLAY 1.021277 (775 -575);
PAINT ORANGE (775 -575);
DISPLAY INVISIBLE (775 -575);
FORCEPROP 1 LAST PATH I232
J 0
(775 -625);
DISPLAY 0.978723 (775 -625);
PAINT WHITE (775 -625);
DISPLAY INVISIBLE (775 -625);
FORCEADD CAP_A..1
(425 -775);
FORCEPROP 1 LASTPIN (425 -875) $PN 2
J 0
(435 -895);
DISPLAY 0.617021 (435 -895);
PAINT ORANGE (435 -895);
FORCEPROP 1 LASTPIN (425 -675) $PN 1
J 0
(435 -695);
DISPLAY 0.617021 (435 -695);
PAINT ORANGE (435 -695);
FORCEPROP 1 LAST LOCATION C8M4
J 0
(475 -675);
DISPLAY 0.617021 (475 -675);
PAINT AQUA (475 -675);
FORCEPROP 1 LAST PART_NUMBER E15431-004
J 0
(475 -925);
DISPLAY 0.617021 (475 -925);
PAINT BLUE (475 -925);
FORCEPROP 1 LAST VALUE 22.0UF
J 0
(475 -725);
DISPLAY 0.617021 (475 -725);
PAINT SKYBLUE (475 -725);
FORCEPROP 1 LAST TOLERANCE 20%
J 0
(475 -825);
DISPLAY 0.617021 (475 -825);
PAINT SKYBLUE (475 -825);
FORCEPROP 1 LAST PACK_TYPE 0603V
J 0
(475 -975);
DISPLAY 0.617021 (475 -975);
PAINT SKYBLUE (475 -975);
FORCEPROP 1 LAST VOLTAGE 4V
J 0
(475 -775);
DISPLAY 0.617021 (475 -775);
PAINT SKYBLUE (475 -775);
FORCEPROP 1 LAST MATERIAL X6S
J 0
(475 -875);
DISPLAY 0.617021 (475 -875);
PAINT SKYBLUE (475 -875);
FORCEPROP 2 LAST CDS_LIB dev_discrete
J 0
(425 -775);
PAINT ORANGE (425 -775);
DISPLAY INVISIBLE (425 -775);
FORCEPROP 2 LAST CDS_LOCATION C8M4
J 0
(475 -675);
DISPLAY 0.617021 (475 -675);
PAINT AQUA (475 -675);
DISPLAY INVISIBLE (475 -675);
FORCEPROP 1 LAST PATH I233
J 0
(475 -625);
DISPLAY 0.978723 (475 -625);
PAINT WHITE (475 -625);
DISPLAY INVISIBLE (475 -625);
FORCEPROP 2 LAST SEC 1
J 0
(475 -625);
DISPLAY 0.680851 (475 -625);
PAINT MONO (475 -625);
DISPLAY INVISIBLE (475 -625);
FORCEPROP 2 LAST SEC_TYPE 0603V
J 0
(475 -575);
DISPLAY 1.021277 (475 -575);
PAINT ORANGE (475 -575);
DISPLAY INVISIBLE (475 -575);
FORCEPROP 2 LAST CDS_SEC 1
J 0
(475 -625);
PAINT ORANGE (475 -625);
DISPLAY INVISIBLE (475 -625);
FORCEPROP 0 LAST ROOM PVDDQ_KLM
J 0
(475 -575);
DISPLAY 1.021277 (475 -575);
PAINT ORANGE (475 -575);
DISPLAY INVISIBLE (475 -575);
FORCEADD CAP_A..1
(125 -775);
FORCEPROP 1 LASTPIN (125 -875) $PN 2
J 0
(135 -895);
DISPLAY 0.617021 (135 -895);
PAINT ORANGE (135 -895);
FORCEPROP 1 LAST VOLTAGE 4V
J 0
(175 -775);
DISPLAY 0.617021 (175 -775);
PAINT SKYBLUE (175 -775);
FORCEPROP 1 LASTPIN (125 -675) $PN 1
J 0
(135 -695);
DISPLAY 0.617021 (135 -695);
PAINT ORANGE (135 -695);
FORCEPROP 1 LAST LOCATION C2A4
J 0
(175 -675);
DISPLAY 0.617021 (175 -675);
PAINT AQUA (175 -675);
FORCEPROP 1 LAST PART_NUMBER E15431-004
J 0
(175 -925);
DISPLAY 0.617021 (175 -925);
PAINT BLUE (175 -925);
FORCEPROP 1 LAST TOLERANCE 20%
J 0
(175 -825);
DISPLAY 0.617021 (175 -825);
PAINT SKYBLUE (175 -825);
FORCEPROP 1 LAST PACK_TYPE 0603V
J 0
(175 -975);
DISPLAY 0.617021 (175 -975);
PAINT SKYBLUE (175 -975);
FORCEPROP 1 LAST MATERIAL X6S
J 0
(175 -875);
DISPLAY 0.617021 (175 -875);
PAINT SKYBLUE (175 -875);
FORCEPROP 1 LAST VALUE 22.0UF
J 0
(175 -725);
DISPLAY 0.617021 (175 -725);
PAINT SKYBLUE (175 -725);
FORCEPROP 2 LAST CDS_LIB dev_discrete
J 0
(125 -775);
PAINT ORANGE (125 -775);
DISPLAY INVISIBLE (125 -775);
FORCEPROP 2 LAST CDS_SEC 1
J 0
(175 -625);
PAINT ORANGE (175 -625);
DISPLAY INVISIBLE (175 -625);
FORCEPROP 2 LAST CDS_LOCATION C2A4
J 0
(175 -675);
DISPLAY 0.617021 (175 -675);
PAINT AQUA (175 -675);
DISPLAY INVISIBLE (175 -675);
FORCEPROP 2 LAST SEC 1
J 0
(175 -575);
DISPLAY 0.680851 (175 -575);
PAINT MONO (175 -575);
DISPLAY INVISIBLE (175 -575);
FORCEPROP 2 LAST SEC_TYPE 0603V
J 0
(175 -575);
DISPLAY 1.021277 (175 -575);
PAINT ORANGE (175 -575);
DISPLAY INVISIBLE (175 -575);
FORCEPROP 0 LAST ROOM PVDDQ_KLM
J 0
(175 -575);
DISPLAY 1.021277 (175 -575);
PAINT ORANGE (175 -575);
DISPLAY INVISIBLE (175 -575);
FORCEPROP 1 LAST PATH I234
J 0
(175 -625);
DISPLAY 0.978723 (175 -625);
PAINT WHITE (175 -625);
DISPLAY INVISIBLE (175 -625);
FORCEADD CAP_A..1
(-200 -775);
FORCEPROP 1 LASTPIN (-200 -875) $PN 2
J 0
(-190 -895);
DISPLAY 0.617021 (-190 -895);
PAINT ORANGE (-190 -895);
FORCEPROP 1 LAST VOLTAGE 4V
J 0
(-150 -775);
DISPLAY 0.617021 (-150 -775);
PAINT SKYBLUE (-150 -775);
FORCEPROP 1 LASTPIN (-200 -675) $PN 1
J 0
(-190 -695);
DISPLAY 0.617021 (-190 -695);
PAINT ORANGE (-190 -695);
FORCEPROP 1 LAST LOCATION C8M6
J 0
(-150 -675);
DISPLAY 0.617021 (-150 -675);
PAINT AQUA (-150 -675);
FORCEPROP 1 LAST VALUE 22.0UF
J 0
(-150 -725);
DISPLAY 0.617021 (-150 -725);
PAINT SKYBLUE (-150 -725);
FORCEPROP 1 LAST TOLERANCE 20%
J 0
(-150 -825);
DISPLAY 0.617021 (-150 -825);
PAINT SKYBLUE (-150 -825);
FORCEPROP 1 LAST MATERIAL X6S
J 0
(-150 -875);
DISPLAY 0.617021 (-150 -875);
PAINT SKYBLUE (-150 -875);
FORCEPROP 1 LAST PART_NUMBER E15431-004
J 0
(-150 -925);
DISPLAY 0.617021 (-150 -925);
PAINT BLUE (-150 -925);
FORCEPROP 1 LAST PACK_TYPE 0603V
J 0
(-150 -975);
DISPLAY 0.617021 (-150 -975);
PAINT SKYBLUE (-150 -975);
FORCEPROP 2 LAST CDS_LIB dev_discrete
J 0
(-200 -775);
PAINT ORANGE (-200 -775);
DISPLAY INVISIBLE (-200 -775);
FORCEPROP 2 LAST CDS_LOCATION C8M6
J 0
(-150 -675);
DISPLAY 0.617021 (-150 -675);
PAINT AQUA (-150 -675);
DISPLAY INVISIBLE (-150 -675);
FORCEPROP 2 LAST CDS_SEC 1
J 0
(-150 -625);
PAINT ORANGE (-150 -625);
DISPLAY INVISIBLE (-150 -625);
FORCEPROP 2 LAST SEC_TYPE 0603V
J 0
(-150 -575);
DISPLAY 1.021277 (-150 -575);
PAINT ORANGE (-150 -575);
DISPLAY INVISIBLE (-150 -575);
FORCEPROP 2 LAST SEC 1
J 0
(-150 -625);
DISPLAY 0.680851 (-150 -625);
PAINT MONO (-150 -625);
DISPLAY INVISIBLE (-150 -625);
FORCEPROP 1 LAST PATH I235
J 0
(-150 -625);
DISPLAY 0.978723 (-150 -625);
PAINT WHITE (-150 -625);
DISPLAY INVISIBLE (-150 -625);
FORCEPROP 0 LAST ROOM PVDDQ_KLM
J 0
(-150 -575);
DISPLAY 1.021277 (-150 -575);
PAINT ORANGE (-150 -575);
DISPLAY INVISIBLE (-150 -575);
FORCEADD CAP_A..1
(-475 -775);
FORCEPROP 1 LASTPIN (-475 -875) $PN 2
J 0
(-465 -895);
DISPLAY 0.617021 (-465 -895);
PAINT ORANGE (-465 -895);
FORCEPROP 1 LAST TOLERANCE 20%
J 0
(-425 -825);
DISPLAY 0.617021 (-425 -825);
PAINT SKYBLUE (-425 -825);
FORCEPROP 1 LAST PACK_TYPE 0603V
J 0
(-425 -975);
DISPLAY 0.617021 (-425 -975);
PAINT SKYBLUE (-425 -975);
FORCEPROP 1 LAST MATERIAL X6S
J 0
(-425 -875);
DISPLAY 0.617021 (-425 -875);
PAINT SKYBLUE (-425 -875);
FORCEPROP 1 LAST VOLTAGE 4V
J 0
(-425 -775);
DISPLAY 0.617021 (-425 -775);
PAINT SKYBLUE (-425 -775);
FORCEPROP 1 LASTPIN (-475 -675) $PN 1
J 0
(-465 -695);
DISPLAY 0.617021 (-465 -695);
PAINT ORANGE (-465 -695);
FORCEPROP 1 LAST LOCATION C8L9
J 0
(-425 -675);
DISPLAY 0.617021 (-425 -675);
PAINT AQUA (-425 -675);
FORCEPROP 1 LAST PART_NUMBER E15431-004
J 0
(-425 -925);
DISPLAY 0.617021 (-425 -925);
PAINT BLUE (-425 -925);
FORCEPROP 1 LAST VALUE 22.0UF
J 0
(-425 -725);
DISPLAY 0.617021 (-425 -725);
PAINT SKYBLUE (-425 -725);
FORCEPROP 2 LAST CDS_LIB dev_discrete
J 0
(-475 -775);
PAINT ORANGE (-475 -775);
DISPLAY INVISIBLE (-475 -775);
FORCEPROP 2 LAST CDS_LOCATION C8L9
J 0
(-425 -675);
DISPLAY 0.617021 (-425 -675);
PAINT AQUA (-425 -675);
DISPLAY INVISIBLE (-425 -675);
FORCEPROP 2 LAST CDS_SEC 1
J 0
(-425 -625);
PAINT ORANGE (-425 -625);
DISPLAY INVISIBLE (-425 -625);
FORCEPROP 2 LAST SEC_TYPE 0603V
J 0
(-425 -575);
DISPLAY 1.021277 (-425 -575);
PAINT ORANGE (-425 -575);
DISPLAY INVISIBLE (-425 -575);
FORCEPROP 2 LAST SEC 1
J 0
(-425 -625);
DISPLAY 0.680851 (-425 -625);
PAINT MONO (-425 -625);
DISPLAY INVISIBLE (-425 -625);
FORCEPROP 1 LAST PATH I236
J 0
(-425 -625);
DISPLAY 0.978723 (-425 -625);
PAINT WHITE (-425 -625);
DISPLAY INVISIBLE (-425 -625);
FORCEPROP 0 LAST ROOM PVDDQ_KLM
J 0
(-425 -575);
DISPLAY 1.021277 (-425 -575);
PAINT ORANGE (-425 -575);
DISPLAY INVISIBLE (-425 -575);
FORCEADD CAP_A..1
(-775 -775);
FORCEPROP 1 LASTPIN (-775 -675) $PN 1
J 0
(-765 -695);
DISPLAY 0.617021 (-765 -695);
PAINT ORANGE (-765 -695);
FORCEPROP 1 LASTPIN (-775 -875) $PN 2
J 0
(-765 -895);
DISPLAY 0.617021 (-765 -895);
PAINT ORANGE (-765 -895);
FORCEPROP 1 LAST MATERIAL X6S
J 0
(-725 -875);
DISPLAY 0.617021 (-725 -875);
PAINT SKYBLUE (-725 -875);
FORCEPROP 1 LAST VOLTAGE 4V
J 0
(-725 -775);
DISPLAY 0.617021 (-725 -775);
PAINT SKYBLUE (-725 -775);
FORCEPROP 1 LAST PACK_TYPE 0603V
J 0
(-725 -975);
DISPLAY 0.617021 (-725 -975);
PAINT SKYBLUE (-725 -975);
FORCEPROP 1 LAST TOLERANCE 20%
J 0
(-725 -825);
DISPLAY 0.617021 (-725 -825);
PAINT SKYBLUE (-725 -825);
FORCEPROP 1 LAST LOCATION C8L8
J 0
(-725 -675);
DISPLAY 0.617021 (-725 -675);
PAINT AQUA (-725 -675);
FORCEPROP 1 LAST VALUE 22.0UF
J 0
(-725 -725);
DISPLAY 0.617021 (-725 -725);
PAINT SKYBLUE (-725 -725);
FORCEPROP 1 LAST PART_NUMBER E15431-004
J 0
(-725 -925);
DISPLAY 0.617021 (-725 -925);
PAINT BLUE (-725 -925);
FORCEPROP 2 LAST CDS_LIB dev_discrete
J 0
(-775 -775);
PAINT ORANGE (-775 -775);
DISPLAY INVISIBLE (-775 -775);
FORCEPROP 2 LAST CDS_LOCATION C8L8
J 0
(-725 -675);
DISPLAY 0.617021 (-725 -675);
PAINT AQUA (-725 -675);
DISPLAY INVISIBLE (-725 -675);
FORCEPROP 2 LAST CDS_SEC 1
J 0
(-725 -625);
PAINT ORANGE (-725 -625);
DISPLAY INVISIBLE (-725 -625);
FORCEPROP 2 LAST SEC_TYPE 0603V
J 0
(-725 -575);
DISPLAY 1.021277 (-725 -575);
PAINT ORANGE (-725 -575);
DISPLAY INVISIBLE (-725 -575);
FORCEPROP 2 LAST SEC 1
J 0
(-725 -625);
DISPLAY 0.680851 (-725 -625);
PAINT MONO (-725 -625);
DISPLAY INVISIBLE (-725 -625);
FORCEPROP 1 LAST PATH I237
J 0
(-725 -625);
DISPLAY 0.978723 (-725 -625);
PAINT WHITE (-725 -625);
DISPLAY INVISIBLE (-725 -625);
FORCEPROP 0 LAST ROOM PVDDQ_KLM
J 0
(-725 -575);
DISPLAY 1.021277 (-725 -575);
PAINT ORANGE (-725 -575);
DISPLAY INVISIBLE (-725 -575);
FORCEADD CAP_A..1
(-1075 -775);
FORCEPROP 1 LASTPIN (-1075 -875) $PN 2
J 0
(-1065 -895);
DISPLAY 0.617021 (-1065 -895);
PAINT ORANGE (-1065 -895);
FORCEPROP 1 LASTPIN (-1075 -675) $PN 1
J 0
(-1065 -695);
DISPLAY 0.617021 (-1065 -695);
PAINT ORANGE (-1065 -695);
FORCEPROP 1 LAST LOCATION C7L4
J 0
(-1025 -675);
DISPLAY 0.617021 (-1025 -675);
PAINT AQUA (-1025 -675);
FORCEPROP 1 LAST PART_NUMBER E15431-004
J 0
(-1025 -925);
DISPLAY 0.617021 (-1025 -925);
PAINT BLUE (-1025 -925);
FORCEPROP 1 LAST VALUE 22.0UF
J 0
(-1025 -725);
DISPLAY 0.617021 (-1025 -725);
PAINT SKYBLUE (-1025 -725);
FORCEPROP 1 LAST TOLERANCE 20%
J 0
(-1025 -825);
DISPLAY 0.617021 (-1025 -825);
PAINT SKYBLUE (-1025 -825);
FORCEPROP 1 LAST PACK_TYPE 0603V
J 0
(-1025 -975);
DISPLAY 0.617021 (-1025 -975);
PAINT SKYBLUE (-1025 -975);
FORCEPROP 1 LAST VOLTAGE 4V
J 0
(-1025 -775);
DISPLAY 0.617021 (-1025 -775);
PAINT SKYBLUE (-1025 -775);
FORCEPROP 1 LAST MATERIAL X6S
J 0
(-1025 -875);
DISPLAY 0.617021 (-1025 -875);
PAINT SKYBLUE (-1025 -875);
FORCEPROP 2 LAST CDS_LIB dev_discrete
J 0
(-1075 -775);
PAINT ORANGE (-1075 -775);
DISPLAY INVISIBLE (-1075 -775);
FORCEPROP 2 LAST CDS_LOCATION C7L4
J 0
(-1025 -675);
DISPLAY 0.617021 (-1025 -675);
PAINT AQUA (-1025 -675);
DISPLAY INVISIBLE (-1025 -675);
FORCEPROP 1 LAST PATH I238
J 0
(-1025 -625);
DISPLAY 0.978723 (-1025 -625);
PAINT WHITE (-1025 -625);
DISPLAY INVISIBLE (-1025 -625);
FORCEPROP 2 LAST SEC 1
J 0
(-1025 -575);
DISPLAY 0.680851 (-1025 -575);
PAINT MONO (-1025 -575);
DISPLAY INVISIBLE (-1025 -575);
FORCEPROP 2 LAST SEC_TYPE 0603V
J 0
(-1025 -575);
DISPLAY 1.021277 (-1025 -575);
PAINT ORANGE (-1025 -575);
DISPLAY INVISIBLE (-1025 -575);
FORCEPROP 2 LAST CDS_SEC 1
J 0
(-1025 -625);
PAINT ORANGE (-1025 -625);
DISPLAY INVISIBLE (-1025 -625);
FORCEPROP 0 LAST ROOM PVDDQ_KLM
J 0
(-1025 -575);
DISPLAY 1.021277 (-1025 -575);
PAINT ORANGE (-1025 -575);
DISPLAY INVISIBLE (-1025 -575);
FORCEADD CAP_A..1
(-1350 -775);
FORCEPROP 1 LASTPIN (-1350 -875) $PN 2
J 0
(-1340 -895);
DISPLAY 0.617021 (-1340 -895);
PAINT ORANGE (-1340 -895);
FORCEPROP 1 LASTPIN (-1350 -675) $PN 1
J 0
(-1340 -695);
DISPLAY 0.617021 (-1340 -695);
PAINT ORANGE (-1340 -695);
FORCEPROP 1 LAST LOCATION C8L7
J 0
(-1300 -675);
DISPLAY 0.617021 (-1300 -675);
PAINT AQUA (-1300 -675);
FORCEPROP 1 LAST VALUE 22.0UF
J 0
(-1300 -725);
DISPLAY 0.617021 (-1300 -725);
PAINT SKYBLUE (-1300 -725);
FORCEPROP 1 LAST PACK_TYPE 0603V
J 0
(-1300 -975);
DISPLAY 0.617021 (-1300 -975);
PAINT SKYBLUE (-1300 -975);
FORCEPROP 1 LAST PART_NUMBER E15431-004
J 0
(-1300 -925);
DISPLAY 0.617021 (-1300 -925);
PAINT BLUE (-1300 -925);
FORCEPROP 1 LAST MATERIAL X6S
J 0
(-1300 -875);
DISPLAY 0.617021 (-1300 -875);
PAINT SKYBLUE (-1300 -875);
FORCEPROP 1 LAST TOLERANCE 20%
J 0
(-1300 -825);
DISPLAY 0.617021 (-1300 -825);
PAINT SKYBLUE (-1300 -825);
FORCEPROP 1 LAST VOLTAGE 4V
J 0
(-1300 -775);
DISPLAY 0.617021 (-1300 -775);
PAINT SKYBLUE (-1300 -775);
FORCEPROP 2 LAST CDS_LIB dev_discrete
J 0
(-1350 -775);
PAINT ORANGE (-1350 -775);
DISPLAY INVISIBLE (-1350 -775);
FORCEPROP 2 LAST CDS_LOCATION C8L7
J 0
(-1300 -675);
DISPLAY 0.617021 (-1300 -675);
PAINT AQUA (-1300 -675);
DISPLAY INVISIBLE (-1300 -675);
FORCEPROP 1 LAST PATH I239
J 0
(-1300 -625);
DISPLAY 0.978723 (-1300 -625);
PAINT WHITE (-1300 -625);
DISPLAY INVISIBLE (-1300 -625);
FORCEPROP 2 LAST SEC 1
J 0
(-1300 -625);
DISPLAY 0.680851 (-1300 -625);
PAINT MONO (-1300 -625);
DISPLAY INVISIBLE (-1300 -625);
FORCEPROP 2 LAST SEC_TYPE 0603V
J 0
(-1300 -575);
DISPLAY 1.021277 (-1300 -575);
PAINT ORANGE (-1300 -575);
DISPLAY INVISIBLE (-1300 -575);
FORCEPROP 2 LAST CDS_SEC 1
J 0
(-1300 -625);
PAINT ORANGE (-1300 -625);
DISPLAY INVISIBLE (-1300 -625);
FORCEPROP 0 LAST ROOM PVDDQ_KLM
J 0
(-1300 -575);
DISPLAY 1.021277 (-1300 -575);
PAINT ORANGE (-1300 -575);
DISPLAY INVISIBLE (-1300 -575);
FORCEADD CAP_A..1
(-1625 -775);
FORCEPROP 1 LASTPIN (-1625 -875) $PN 2
J 0
(-1615 -895);
DISPLAY 0.617021 (-1615 -895);
PAINT ORANGE (-1615 -895);
FORCEPROP 1 LASTPIN (-1625 -675) $PN 1
J 0
(-1615 -695);
DISPLAY 0.617021 (-1615 -695);
PAINT ORANGE (-1615 -695);
FORCEPROP 1 LAST LOCATION C8L6
J 0
(-1575 -675);
DISPLAY 0.617021 (-1575 -675);
PAINT AQUA (-1575 -675);
FORCEPROP 1 LAST PART_NUMBER E15431-004
J 0
(-1575 -925);
DISPLAY 0.617021 (-1575 -925);
PAINT BLUE (-1575 -925);
FORCEPROP 1 LAST VALUE 22.0UF
J 0
(-1575 -725);
DISPLAY 0.617021 (-1575 -725);
PAINT SKYBLUE (-1575 -725);
FORCEPROP 1 LAST TOLERANCE 20%
J 0
(-1575 -825);
DISPLAY 0.617021 (-1575 -825);
PAINT SKYBLUE (-1575 -825);
FORCEPROP 1 LAST VOLTAGE 4V
J 0
(-1575 -775);
DISPLAY 0.617021 (-1575 -775);
PAINT SKYBLUE (-1575 -775);
FORCEPROP 1 LAST MATERIAL X6S
J 0
(-1575 -875);
DISPLAY 0.617021 (-1575 -875);
PAINT SKYBLUE (-1575 -875);
FORCEPROP 1 LAST PACK_TYPE 0603V
J 0
(-1575 -975);
DISPLAY 0.617021 (-1575 -975);
PAINT SKYBLUE (-1575 -975);
FORCEPROP 2 LAST CDS_LIB dev_discrete
J 0
(-1625 -775);
PAINT ORANGE (-1625 -775);
DISPLAY INVISIBLE (-1625 -775);
FORCEPROP 2 LAST CDS_LOCATION C8L6
J 0
(-1575 -675);
DISPLAY 0.617021 (-1575 -675);
PAINT AQUA (-1575 -675);
DISPLAY INVISIBLE (-1575 -675);
FORCEPROP 1 LAST PATH I240
J 0
(-1575 -625);
DISPLAY 0.978723 (-1575 -625);
PAINT WHITE (-1575 -625);
DISPLAY INVISIBLE (-1575 -625);
FORCEPROP 2 LAST SEC 1
J 0
(-1575 -625);
DISPLAY 0.680851 (-1575 -625);
PAINT MONO (-1575 -625);
DISPLAY INVISIBLE (-1575 -625);
FORCEPROP 2 LAST SEC_TYPE 0603V
J 0
(-1575 -575);
DISPLAY 1.021277 (-1575 -575);
PAINT ORANGE (-1575 -575);
DISPLAY INVISIBLE (-1575 -575);
FORCEPROP 2 LAST CDS_SEC 1
J 0
(-1575 -625);
PAINT ORANGE (-1575 -625);
DISPLAY INVISIBLE (-1575 -625);
FORCEPROP 0 LAST ROOM PVDDQ_KLM
J 0
(-1575 -575);
DISPLAY 1.021277 (-1575 -575);
PAINT ORANGE (-1575 -575);
DISPLAY INVISIBLE (-1575 -575);
FORCEADD CAP_A..1
(-1925 -775);
FORCEPROP 1 LASTPIN (-1925 -675) $PN 1
J 0
(-1915 -695);
DISPLAY 0.617021 (-1915 -695);
PAINT ORANGE (-1915 -695);
FORCEPROP 1 LAST PACK_TYPE 0603V
J 0
(-1875 -975);
DISPLAY 0.617021 (-1875 -975);
PAINT SKYBLUE (-1875 -975);
FORCEPROP 1 LASTPIN (-1925 -875) $PN 2
J 0
(-1915 -895);
DISPLAY 0.617021 (-1915 -895);
PAINT ORANGE (-1915 -895);
FORCEPROP 1 LAST MATERIAL X6S
J 0
(-1875 -875);
DISPLAY 0.617021 (-1875 -875);
PAINT SKYBLUE (-1875 -875);
FORCEPROP 1 LAST TOLERANCE 20%
J 0
(-1875 -825);
DISPLAY 0.617021 (-1875 -825);
PAINT SKYBLUE (-1875 -825);
FORCEPROP 1 LAST VOLTAGE 4V
J 0
(-1875 -775);
DISPLAY 0.617021 (-1875 -775);
PAINT SKYBLUE (-1875 -775);
FORCEPROP 1 LAST LOCATION C8L5
J 0
(-1875 -675);
DISPLAY 0.617021 (-1875 -675);
PAINT AQUA (-1875 -675);
FORCEPROP 1 LAST VALUE 22.0UF
J 0
(-1875 -725);
DISPLAY 0.617021 (-1875 -725);
PAINT SKYBLUE (-1875 -725);
FORCEPROP 1 LAST PART_NUMBER E15431-004
J 0
(-1875 -925);
DISPLAY 0.617021 (-1875 -925);
PAINT BLUE (-1875 -925);
FORCEPROP 2 LAST CDS_LIB dev_discrete
J 0
(-1925 -775);
PAINT ORANGE (-1925 -775);
DISPLAY INVISIBLE (-1925 -775);
FORCEPROP 2 LAST CDS_SEC 1
J 0
(-1875 -625);
PAINT ORANGE (-1875 -625);
DISPLAY INVISIBLE (-1875 -625);
FORCEPROP 2 LAST CDS_LOCATION C8L5
J 0
(-1875 -675);
DISPLAY 0.617021 (-1875 -675);
PAINT AQUA (-1875 -675);
DISPLAY INVISIBLE (-1875 -675);
FORCEPROP 2 LAST SEC 1
J 0
(-1875 -625);
DISPLAY 0.680851 (-1875 -625);
PAINT MONO (-1875 -625);
DISPLAY INVISIBLE (-1875 -625);
FORCEPROP 2 LAST SEC_TYPE 0603V
J 0
(-1875 -575);
DISPLAY 1.021277 (-1875 -575);
PAINT ORANGE (-1875 -575);
DISPLAY INVISIBLE (-1875 -575);
FORCEPROP 0 LAST ROOM PVDDQ_KLM
J 0
(-1875 -575);
DISPLAY 1.021277 (-1875 -575);
PAINT ORANGE (-1875 -575);
DISPLAY INVISIBLE (-1875 -575);
FORCEPROP 1 LAST PATH I241
J 0
(-1875 -625);
DISPLAY 0.978723 (-1875 -625);
PAINT WHITE (-1875 -625);
DISPLAY INVISIBLE (-1875 -625);
FORCEADD PVDDQ_KLM..1
(-2225 -525);
FORCEPROP 3 LASTPIN (-2225 -575) SIG_NAME PVDDQ_KLM\g
J 0
(-2215 -565);
DISPLAY 0.659574 (-2215 -565);
PAINT MONO (-2215 -565);
DISPLAY INVISIBLE (-2215 -565);
FORCEPROP 1 LAST VOLTAGE 1.2V
J 0
(-2270 -568);
DISPLAY 0.340426 (-2270 -568);
PAINT SKYBLUE (-2270 -568);
DISPLAY INVISIBLE (-2270 -568);
FORCEPROP 2 LAST CDS_LIB mstr_symbols
J 0
(-2225 -525);
PAINT ORANGE (-2225 -525);
DISPLAY INVISIBLE (-2225 -525);
FORCEPROP 2 LAST ROOM VDDQ_KLM_PWR_VR
J 0
(-2225 -425);
DISPLAY 1.936170 (-2225 -425);
PAINT ORANGE (-2225 -425);
DISPLAY INVISIBLE (-2225 -425);
FORCEPROP 2 LAST BOM_COST VDDQ_KLM_PWR_VR
J 0
(-2225 -425);
DISPLAY 1.446809 (-2225 -425);
PAINT MONO (-2225 -425);
DISPLAY INVISIBLE (-2225 -425);
FORCEPROP 1 LAST PATH I242
J 0
(-2175 -500);
DISPLAY 0.872340 (-2175 -500);
PAINT AQUA (-2175 -500);
DISPLAY INVISIBLE (-2175 -500);
FORCEPROP 1 LAST BODY_TYPE PLUMBING
J 0
(-2270 -568);
DISPLAY 0.340426 (-2270 -568);
PAINT GREEN (-2270 -568);
DISPLAY INVISIBLE (-2270 -568);
FORCEPROP 1 LAST HDL_POWER PVDDQ_KLM
J 1
(-2225 -475);
DISPLAY 0.872340 (-2225 -475);
PAINT GREEN (-2225 -475);
DISPLAY INVISIBLE (-2225 -475);
FORCEADD CAP_A..1
(-2225 -775);
FORCEPROP 1 LAST VOLTAGE 4V
J 0
(-2175 -775);
DISPLAY 0.617021 (-2175 -775);
PAINT SKYBLUE (-2175 -775);
FORCEPROP 1 LASTPIN (-2225 -675) $PN 1
J 0
(-2215 -695);
DISPLAY 0.617021 (-2215 -695);
PAINT ORANGE (-2215 -695);
FORCEPROP 1 LASTPIN (-2225 -875) $PN 2
J 0
(-2215 -895);
DISPLAY 0.617021 (-2215 -895);
PAINT ORANGE (-2215 -895);
FORCEPROP 1 LAST PACK_TYPE 0603V
J 0
(-2175 -975);
DISPLAY 0.617021 (-2175 -975);
PAINT SKYBLUE (-2175 -975);
FORCEPROP 1 LAST PART_NUMBER E15431-004
J 0
(-2175 -925);
DISPLAY 0.617021 (-2175 -925);
PAINT BLUE (-2175 -925);
FORCEPROP 1 LAST MATERIAL X6S
J 0
(-2175 -875);
DISPLAY 0.617021 (-2175 -875);
PAINT SKYBLUE (-2175 -875);
FORCEPROP 1 LAST TOLERANCE 20%
J 0
(-2175 -825);
DISPLAY 0.617021 (-2175 -825);
PAINT SKYBLUE (-2175 -825);
FORCEPROP 1 LAST VALUE 22.0UF
J 0
(-2175 -725);
DISPLAY 0.617021 (-2175 -725);
PAINT SKYBLUE (-2175 -725);
FORCEPROP 1 LAST LOCATION C8M1
J 0
(-2175 -675);
DISPLAY 0.617021 (-2175 -675);
PAINT AQUA (-2175 -675);
FORCEPROP 2 LAST CDS_LIB dev_discrete
J 0
(-2225 -775);
PAINT ORANGE (-2225 -775);
DISPLAY INVISIBLE (-2225 -775);
FORCEPROP 0 LAST ROOM PVDDQ_KLM
J 0
(-2175 -575);
DISPLAY 1.021277 (-2175 -575);
PAINT ORANGE (-2175 -575);
DISPLAY INVISIBLE (-2175 -575);
FORCEPROP 1 LAST PATH I243
J 0
(-2175 -625);
DISPLAY 0.978723 (-2175 -625);
PAINT WHITE (-2175 -625);
DISPLAY INVISIBLE (-2175 -625);
FORCEPROP 2 LAST SEC 1
J 0
(-2175 -575);
DISPLAY 0.680851 (-2175 -575);
PAINT MONO (-2175 -575);
DISPLAY INVISIBLE (-2175 -575);
FORCEPROP 2 LAST SEC_TYPE 0603V
J 0
(-2175 -575);
DISPLAY 1.021277 (-2175 -575);
PAINT ORANGE (-2175 -575);
DISPLAY INVISIBLE (-2175 -575);
FORCEPROP 2 LAST CDS_SEC 1
J 0
(-2175 -625);
PAINT ORANGE (-2175 -625);
DISPLAY INVISIBLE (-2175 -625);
FORCEPROP 2 LAST CDS_LOCATION C8M1
J 0
(-2175 -675);
DISPLAY 0.617021 (-2175 -675);
PAINT AQUA (-2175 -675);
DISPLAY INVISIBLE (-2175 -675);
FORCEADD GND..1
(-2225 -1050);
FORCEPROP 3 LASTPIN (-2225 -1000) SIG_NAME GND\g
J 0
(-2215 -990);
DISPLAY 0.659574 (-2215 -990);
PAINT MONO (-2215 -990);
DISPLAY INVISIBLE (-2215 -990);
FORCEPROP 1 LAST SIZE 1B
J 0
(-2150 -1100);
DISPLAY 1.723404 (-2150 -1100);
PAINT GREEN (-2150 -1100);
DISPLAY INVISIBLE (-2150 -1100);
FORCEPROP 1 LAST VOLTAGE 0
J 0
(-2225 -1050);
PAINT SKYBLUE (-2225 -1050);
DISPLAY INVISIBLE (-2225 -1050);
FORCEPROP 2 LAST CDS_LIB mstr_symbols
J 0
(-2225 -1050);
PAINT ORANGE (-2225 -1050);
DISPLAY INVISIBLE (-2225 -1050);
FORCEPROP 1 LAST PATH I244
J 0
(-2150 -1050);
DISPLAY 0.872340 (-2150 -1050);
PAINT AQUA (-2150 -1050);
DISPLAY INVISIBLE (-2150 -1050);
FORCEPROP 2 LAST BOM_COST PROC_VRD_VCCIN_CPU0
J 0
(-2600 -975);
DISPLAY 1.446809 (-2600 -975);
PAINT MONO (-2600 -975);
DISPLAY INVISIBLE (-2600 -975);
FORCEPROP 2 LAST ROOM VDDQ_ABC_PWR_VR
J 0
(-2775 -975);
DISPLAY 1.936170 (-2775 -975);
PAINT ORANGE (-2775 -975);
DISPLAY INVISIBLE (-2775 -975);
FORCEPROP 1 LAST BODY_TYPE PLUMBING
J 0
(-2270 -1093);
DISPLAY 0.340426 (-2270 -1093);
PAINT GREEN (-2270 -1093);
DISPLAY INVISIBLE (-2270 -1093);
FORCEPROP 1 LAST HDL_POWER GND
J 0
(-2225 -900);
DISPLAY 1.723404 (-2225 -900);
PAINT GREEN (-2225 -900);
DISPLAY INVISIBLE (-2225 -900);
FORCEADD SHUNT..1
(75 2175);
FORCEPROP 1 LASTPIN (-75 2175) $PN 1
J 2
(-25 2185);
DISPLAY 0.617021 (-25 2185);
PAINT ORANGE (-25 2185);
FORCEPROP 1 LAST LOCATION SH7L2
J 0
(0 2225);
DISPLAY 0.617021 (0 2225);
PAINT AQUA (0 2225);
FORCEPROP 1 LAST PART_NUMBER N_A
J 0
(0 2085);
DISPLAY 0.617021 (0 2085);
PAINT BLUE (0 2085);
FORCEPROP 1 LASTPIN (225 2175) $PN 2
J 0
(185 2185);
DISPLAY 0.617021 (185 2185);
PAINT ORANGE (185 2185);
FORCEPROP 1 LAST MATERIAL EMPTY
J 0
(0 2040);
DISPLAY 0.978723 (0 2040);
PAINT RED (0 2040);
DISPLAY INVISIBLE (0 2040);
FORCEPROP 0 LAST SEC 1
J 0
(0 2275);
DISPLAY 0.680851 (0 2275);
PAINT MONO (0 2275);
DISPLAY INVISIBLE (0 2275);
FORCEPROP 1 LAST PIN_SHORT A:B
J 0
(0 1925);
DISPLAY 1.021277 (0 1925);
PAINT ORANGE (0 1925);
DISPLAY INVISIBLE (0 1925);
FORCEPROP 1 LAST PACK_TYPE SH0201
J 0
(15 1990);
DISPLAY 0.978723 (15 1990);
PAINT SKYBLUE (15 1990);
DISPLAY INVISIBLE (15 1990);
FORCEPROP 2 LAST CDS_LIB mstr_misc
J 0
(75 2175);
PAINT ORANGE (75 2175);
DISPLAY INVISIBLE (75 2175);
FORCEPROP 1 LAST PATH I245
J 0
(25 2275);
DISPLAY 0.978723 (25 2275);
PAINT ORANGE (25 2275);
DISPLAY INVISIBLE (25 2275);
FORCEPROP 2 LAST SEC_TYPE SH0201
J 0
(25 2325);
DISPLAY 1.021277 (25 2325);
PAINT ORANGE (25 2325);
DISPLAY INVISIBLE (25 2325);
FORCEADD SHUNT..1
(75 1725);
FORCEPROP 1 LASTPIN (-75 1725) $PN 1
J 2
(-25 1735);
DISPLAY 0.617021 (-25 1735);
PAINT ORANGE (-25 1735);
FORCEPROP 1 LAST LOCATION SH7L1
J 0
(0 1775);
DISPLAY 0.617021 (0 1775);
PAINT AQUA (0 1775);
FORCEPROP 1 LAST PART_NUMBER N_A
J 0
(0 1635);
DISPLAY 0.617021 (0 1635);
PAINT BLUE (0 1635);
FORCEPROP 1 LASTPIN (225 1725) $PN 2
J 0
(185 1735);
DISPLAY 0.617021 (185 1735);
PAINT ORANGE (185 1735);
FORCEPROP 1 LAST MATERIAL EMPTY
J 0
(0 1590);
DISPLAY 0.978723 (0 1590);
PAINT RED (0 1590);
DISPLAY INVISIBLE (0 1590);
FORCEPROP 0 LAST SEC 1
J 0
(0 1825);
DISPLAY 0.680851 (0 1825);
PAINT MONO (0 1825);
DISPLAY INVISIBLE (0 1825);
FORCEPROP 1 LAST PIN_SHORT A:B
J 0
(0 1475);
DISPLAY 1.021277 (0 1475);
PAINT ORANGE (0 1475);
DISPLAY INVISIBLE (0 1475);
FORCEPROP 1 LAST PACK_TYPE SH0201
J 0
(15 1540);
DISPLAY 0.978723 (15 1540);
PAINT SKYBLUE (15 1540);
DISPLAY INVISIBLE (15 1540);
FORCEPROP 2 LAST CDS_LIB mstr_misc
J 0
(75 1725);
PAINT ORANGE (75 1725);
DISPLAY INVISIBLE (75 1725);
FORCEPROP 2 LAST SEC_TYPE SH0201
J 0
(25 1875);
DISPLAY 1.021277 (25 1875);
PAINT ORANGE (25 1875);
DISPLAY INVISIBLE (25 1875);
FORCEPROP 1 LAST PATH I246
J 0
(25 1825);
DISPLAY 0.978723 (25 1825);
PAINT ORANGE (25 1825);
DISPLAY INVISIBLE (25 1825);
FORCEADD RES..2
(4525 -500);
FORCEPROP 1 LASTPIN (4525 -600) $PN 2
J 0
(4530 -590);
DISPLAY 0.617021 (4530 -590);
PAINT GREEN (4530 -590);
FORCEPROP 1 LASTPIN (4525 -400) $PN 1
J 0
(4530 -438);
DISPLAY 0.617021 (4530 -438);
PAINT GREEN (4530 -438);
FORCEPROP 1 LAST LOCATION R1A1
J 0
(4570 -375);
DISPLAY 0.617021 (4570 -375);
PAINT AQUA (4570 -375);
FORCEPROP 1 LAST PART_NUMBER G22026-003
J 0
(4565 -625);
DISPLAY 0.617021 (4565 -625);
PAINT BLUE (4565 -625);
FORCEPROP 1 LAST VALUE 120.0
J 0
(4570 -425);
DISPLAY 0.617021 (4570 -425);
PAINT SKYBLUE (4570 -425);
FORCEPROP 1 LAST TOLERANCE 1%
J 0
(4570 -475);
DISPLAY 0.617021 (4570 -475);
PAINT SKYBLUE (4570 -475);
FORCEPROP 1 LAST PACK_TYPE 0603
J 0
(4565 -675);
DISPLAY 0.617021 (4565 -675);
PAINT SKYBLUE (4565 -675);
FORCEPROP 1 LAST MATERIAL CHIP
J 0
(4565 -575);
DISPLAY 0.617021 (4565 -575);
PAINT SKYBLUE (4565 -575);
FORCEPROP 1 LAST WATTAGE 1/10W
J 0
(4565 -525);
DISPLAY 0.617021 (4565 -525);
PAINT SKYBLUE (4565 -525);
FORCEPROP 2 LAST CDS_LIB mstr_discrete
J 0
(4525 -500);
PAINT ORANGE (4525 -500);
DISPLAY INVISIBLE (4525 -500);
FORCEPROP 2 LAST ROOM VDDQ_KLM_PWR_VR
J 0
(4575 -325);
PAINT MONO (4575 -325);
DISPLAY INVISIBLE (4575 -325);
FORCEPROP 1 LAST PATH I58
J 0
(4575 -325);
DISPLAY 0.978723 (4575 -325);
PAINT GREEN (4575 -325);
DISPLAY INVISIBLE (4575 -325);
FORCEPROP 2 LAST CDS_LOCATION R1A1
J 0
(4570 -375);
DISPLAY 0.617021 (4570 -375);
PAINT AQUA (4570 -375);
DISPLAY INVISIBLE (4570 -375);
FORCEPROP 2 LAST BOM_COST MEM_VRD_PVPP_AB
J 0
(4575 -325);
PAINT MONO (4575 -325);
DISPLAY INVISIBLE (4575 -325);
FORCEPROP 2 LAST $SEC 1
J 0
(4575 -275);
PAINT MONO (4575 -275);
DISPLAY INVISIBLE (4575 -275);
FORCEPROP 2 LAST CDS_SEC 1
J 0
(4575 -275);
PAINT MONO (4575 -275);
DISPLAY INVISIBLE (4575 -275);
FORCEADD GND..1
(275 1500);
FORCEPROP 3 LASTPIN (275 1550) SIG_NAME GND\g
J 0
(285 1560);
DISPLAY 0.659574 (285 1560);
PAINT MONO (285 1560);
DISPLAY INVISIBLE (285 1560);
FORCEPROP 2 LAST ROOM VDDQ_KLM_PWR_VR
J 0
(-275 1575);
PAINT ORANGE (-275 1575);
DISPLAY INVISIBLE (-275 1575);
FORCEPROP 2 LAST BOM_COST MEM_VRD_PVPP_AB
J 0
(-50 1575);
PAINT MONO (-50 1575);
DISPLAY INVISIBLE (-50 1575);
FORCEPROP 1 LAST SIZE 1B
J 0
(350 1450);
DISPLAY 0.893617 (350 1450);
PAINT GREEN (350 1450);
DISPLAY INVISIBLE (350 1450);
FORCEPROP 1 LAST VOLTAGE 0
J 0
(275 1500);
PAINT SKYBLUE (275 1500);
DISPLAY INVISIBLE (275 1500);
FORCEPROP 2 LAST CDS_LIB mstr_symbols
J 0
(275 1500);
PAINT ORANGE (275 1500);
DISPLAY INVISIBLE (275 1500);
FORCEPROP 1 LAST PATH I65
J 0
(350 1500);
DISPLAY 1.170213 (350 1500);
PAINT AQUA (350 1500);
DISPLAY INVISIBLE (350 1500);
FORCEPROP 1 LAST BODY_TYPE PLUMBING
J 0
(230 1457);
DISPLAY 0.340426 (230 1457);
PAINT GREEN (230 1457);
DISPLAY INVISIBLE (230 1457);
FORCEPROP 1 LAST HDL_POWER GND
J 0
(275 1650);
DISPLAY 0.893617 (275 1650);
PAINT GREEN (275 1650);
DISPLAY INVISIBLE (275 1650);
FORCEADD OFFPAGE..1
(-1625 1800);
FORCEPROP 2 LAST $XR0 226 
J 0
(-1877 1800);
DISPLAY 0.638298 (-1877 1800);
PAINT MONO (-1877 1800);
FORCEPROP 2 LAST BOM_COST MEM_VRD_PVPP_AB
J 0
(-1900 1850);
PAINT MONO (-1900 1850);
DISPLAY INVISIBLE (-1900 1850);
FORCEPROP 2 LAST PATH I70
J 0
(-1555 1870);
DISPLAY 1.361702 (-1555 1870);
PAINT ORANGE (-1555 1870);
DISPLAY INVISIBLE (-1555 1870);
FORCEPROP 2 LAST CDS_LIB mstr_standard
J 0
(-1625 1800);
PAINT ORANGE (-1625 1800);
DISPLAY INVISIBLE (-1625 1800);
FORCEPROP 1 LAST OFFPAGE TRUE
J 0
(-1300 1675);
DISPLAY 0.893617 (-1300 1675);
PAINT GREEN (-1300 1675);
DISPLAY INVISIBLE (-1300 1675);
FORCEPROP 1 LAST COMMENT_BODY TRUE
J 0
(-1500 1700);
DISPLAY 0.893617 (-1500 1700);
PAINT GREEN (-1500 1700);
DISPLAY INVISIBLE (-1500 1700);
FORCEADD OFFPAGE..1
(-1650 2150);
FORCEPROP 2 LAST $XR0 226 
J 0
(-1902 2150);
DISPLAY 0.638298 (-1902 2150);
PAINT MONO (-1902 2150);
FORCEPROP 2 LAST PATH I72
J 0
(-1600 2225);
DISPLAY 1.361702 (-1600 2225);
PAINT ORANGE (-1600 2225);
DISPLAY INVISIBLE (-1600 2225);
FORCEPROP 2 LAST CDS_LIB mstr_standard
J 0
(-1650 2150);
PAINT ORANGE (-1650 2150);
DISPLAY INVISIBLE (-1650 2150);
FORCEPROP 1 LAST OFFPAGE TRUE
J 0
(-1325 2025);
DISPLAY 1.170213 (-1325 2025);
PAINT GREEN (-1325 2025);
DISPLAY INVISIBLE (-1325 2025);
FORCEPROP 1 LAST COMMENT_BODY TRUE
J 0
(-1525 2050);
DISPLAY 1.170213 (-1525 2050);
PAINT GREEN (-1525 2050);
DISPLAY INVISIBLE (-1525 2050);
FORCEADD PVDDQ_KLM..1
(300 2375);
FORCEPROP 3 LASTPIN (300 2325) SIG_NAME PVDDQ_KLM\g
J 0
(310 2335);
DISPLAY 0.659574 (310 2335);
PAINT MONO (310 2335);
DISPLAY INVISIBLE (310 2335);
FORCEPROP 1 LAST VOLTAGE 1.2V
J 0
(255 2332);
DISPLAY 0.340426 (255 2332);
PAINT SKYBLUE (255 2332);
DISPLAY INVISIBLE (255 2332);
FORCEPROP 2 LAST CDS_LIB mstr_symbols
J 0
(300 2375);
PAINT ORANGE (300 2375);
DISPLAY INVISIBLE (300 2375);
FORCEPROP 2 LAST BOM_COST MEM_VRD_PVPP_AB
J 0
(325 2475);
PAINT MONO (325 2475);
DISPLAY INVISIBLE (325 2475);
FORCEPROP 1 LAST PATH I73
J 0
(350 2400);
DISPLAY 0.872340 (350 2400);
PAINT AQUA (350 2400);
DISPLAY INVISIBLE (350 2400);
FORCEPROP 2 LAST ROOM VDDQ_KLM_PWR_VR
J 0
(550 2475);
PAINT ORANGE (550 2475);
DISPLAY INVISIBLE (550 2475);
FORCEPROP 1 LAST BODY_TYPE PLUMBING
J 0
(255 2332);
DISPLAY 0.340426 (255 2332);
PAINT GREEN (255 2332);
DISPLAY INVISIBLE (255 2332);
FORCEPROP 1 LAST HDL_POWER PVDDQ_KLM
J 1
(300 2425);
DISPLAY 0.872340 (300 2425);
PAINT GREEN (300 2425);
DISPLAY INVISIBLE (300 2425);
FORCEADD RES..2
(-375 1925);
FORCEPROP 1 LASTPIN (-375 1825) $PN 2
J 0
(-370 1835);
DISPLAY 0.617021 (-370 1835);
PAINT ORANGE (-370 1835);
FORCEPROP 1 LASTPIN (-375 2025) $PN 1
J 0
(-370 1987);
DISPLAY 0.617021 (-370 1987);
PAINT ORANGE (-370 1987);
FORCEPROP 1 LAST TOLERANCE 1%
J 0
(-330 1950);
DISPLAY 0.617021 (-330 1950);
PAINT SKYBLUE (-330 1950);
FORCEPROP 1 LAST MATERIAL EMPTY
J 0
(-335 1850);
DISPLAY 0.617021 (-335 1850);
PAINT RED (-335 1850);
FORCEPROP 1 LAST PART_NUMBER G21796-017
J 0
(-335 1800);
DISPLAY 0.617021 (-335 1800);
PAINT BLUE (-335 1800);
FORCEPROP 1 LAST VALUE 100.0
J 0
(-330 2000);
DISPLAY 0.617021 (-330 2000);
PAINT SKYBLUE (-330 2000);
FORCEPROP 1 LAST PACK_TYPE 0402
J 0
(-335 1750);
DISPLAY 0.617021 (-335 1750);
PAINT SKYBLUE (-335 1750);
FORCEPROP 1 LAST WATTAGE 1/16W
J 0
(-335 1900);
DISPLAY 0.617021 (-335 1900);
PAINT SKYBLUE (-335 1900);
FORCEPROP 1 LAST LOCATION R7L2
J 0
(-330 2050);
DISPLAY 0.617021 (-330 2050);
PAINT AQUA (-330 2050);
FORCEPROP 2 LAST CDS_LIB mstr_discrete
J 0
(-375 1925);
PAINT ORANGE (-375 1925);
DISPLAY INVISIBLE (-375 1925);
FORCEPROP 1 LAST PATH I74
J 0
(-325 2100);
DISPLAY 1.319149 (-325 2100);
PAINT WHITE (-325 2100);
DISPLAY INVISIBLE (-325 2100);
FORCEPROP 2 LAST CDS_LOCATION R7L2
J 0
(-330 2050);
DISPLAY 0.617021 (-330 2050);
PAINT AQUA (-330 2050);
DISPLAY INVISIBLE (-330 2050);
FORCEPROP 2 LAST SEC 1
J 0
(-325 2175);
DISPLAY 0.680851 (-325 2175);
PAINT MONO (-325 2175);
DISPLAY INVISIBLE (-325 2175);
FORCEPROP 0 LAST ROOM VDDQ_KLM_PWR_VR
J 0
(-325 2100);
DISPLAY 1.021277 (-325 2100);
PAINT ORANGE (-325 2100);
DISPLAY INVISIBLE (-325 2100);
FORCEPROP 2 LAST SEC_TYPE 0402
J 0
(-325 2175);
DISPLAY 1.021277 (-325 2175);
PAINT ORANGE (-325 2175);
DISPLAY INVISIBLE (-325 2175);
FORCEADD CAPP..1
(2900 -475);
FORCEPROP 1 LAST PACK_TYPE 3018
J 0
(2950 -625);
DISPLAY 0.617021 (2950 -625);
PAINT SKYBLUE (2950 -625);
FORCEPROP 1 LAST MATERIAL ALUM
J 0
(2950 -575);
DISPLAY 0.617021 (2950 -575);
PAINT SKYBLUE (2950 -575);
FORCEPROP 1 LASTPIN (2900 -575) $PN 2
J 0
(2910 -590);
DISPLAY 0.617021 (2910 -590);
PAINT ORANGE (2910 -590);
FORCEPROP 1 LAST VOLTAGE 2.5V
J 0
(2950 -525);
DISPLAY 0.617021 (2950 -525);
PAINT SKYBLUE (2950 -525);
FORCEPROP 1 LASTPIN (2900 -375) $PN 1
J 0
(2910 -390);
DISPLAY 0.617021 (2910 -390);
PAINT ORANGE (2910 -390);
FORCEPROP 1 LAST LOCATION C9L9
J 0
(2950 -375);
DISPLAY 0.617021 (2950 -375);
PAINT AQUA (2950 -375);
FORCEPROP 1 LAST TOLERANCE 20%
J 0
(2950 -475);
DISPLAY 0.617021 (2950 -475);
PAINT SKYBLUE (2950 -475);
FORCEPROP 1 LAST PART_NUMBER 699013-049
J 0
(2950 -675);
DISPLAY 0.617021 (2950 -675);
PAINT BLUE (2950 -675);
FORCEPROP 1 LAST VALUE 470UF
J 0
(2950 -425);
DISPLAY 0.617021 (2950 -425);
PAINT SKYBLUE (2950 -425);
FORCEPROP 2 LAST CDS_LIB mstr_discrete
J 0
(2900 -475);
PAINT ORANGE (2900 -475);
DISPLAY INVISIBLE (2900 -475);
FORCEPROP 2 LAST CDS_LOCATION C9L9
J 0
(2950 -375);
DISPLAY 0.617021 (2950 -375);
PAINT AQUA (2950 -375);
DISPLAY INVISIBLE (2950 -375);
FORCEPROP 1 LAST PATH I75
J 0
(2950 -325);
DISPLAY 1.319149 (2950 -325);
PAINT ORANGE (2950 -325);
DISPLAY INVISIBLE (2950 -325);
FORCEPROP 0 LAST ROOM VDDQ_KLM_PWR_VR
J 0
(2950 -325);
DISPLAY 1.021277 (2950 -325);
PAINT ORANGE (2950 -325);
DISPLAY INVISIBLE (2950 -325);
FORCEPROP 2 LAST SEC_TYPE 3018
J 0
(2950 -250);
DISPLAY 1.021277 (2950 -250);
PAINT ORANGE (2950 -250);
DISPLAY INVISIBLE (2950 -250);
FORCEPROP 2 LAST SEC 1
J 0
(2950 -250);
DISPLAY 0.680851 (2950 -250);
PAINT MONO (2950 -250);
DISPLAY INVISIBLE (2950 -250);
FORCEADD CAPP..1
(3325 -475);
FORCEPROP 1 LAST PACK_TYPE 3018
J 0
(3375 -625);
DISPLAY 0.617021 (3375 -625);
PAINT SKYBLUE (3375 -625);
FORCEPROP 1 LAST MATERIAL ALUM
J 0
(3375 -575);
DISPLAY 0.617021 (3375 -575);
PAINT SKYBLUE (3375 -575);
FORCEPROP 1 LASTPIN (3325 -575) $PN 2
J 0
(3335 -590);
DISPLAY 0.617021 (3335 -590);
PAINT ORANGE (3335 -590);
FORCEPROP 1 LAST VOLTAGE 2.5V
J 0
(3375 -525);
DISPLAY 0.617021 (3375 -525);
PAINT SKYBLUE (3375 -525);
FORCEPROP 1 LASTPIN (3325 -375) $PN 1
J 0
(3335 -390);
DISPLAY 0.617021 (3335 -390);
PAINT ORANGE (3335 -390);
FORCEPROP 1 LAST TOLERANCE 20%
J 0
(3375 -475);
DISPLAY 0.617021 (3375 -475);
PAINT SKYBLUE (3375 -475);
FORCEPROP 1 LAST VALUE 470UF
J 0
(3375 -425);
DISPLAY 0.617021 (3375 -425);
PAINT SKYBLUE (3375 -425);
FORCEPROP 1 LAST LOCATION C9L12
J 0
(3375 -375);
DISPLAY 0.617021 (3375 -375);
PAINT AQUA (3375 -375);
FORCEPROP 1 LAST PART_NUMBER 699013-049
J 0
(3375 -675);
DISPLAY 0.617021 (3375 -675);
PAINT BLUE (3375 -675);
FORCEPROP 2 LAST CDS_LIB mstr_discrete
J 0
(3325 -475);
PAINT ORANGE (3325 -475);
DISPLAY INVISIBLE (3325 -475);
FORCEPROP 0 LAST ROOM VDDQ_KLM_PWR_VR
J 0
(3375 -325);
DISPLAY 1.021277 (3375 -325);
PAINT ORANGE (3375 -325);
DISPLAY INVISIBLE (3375 -325);
FORCEPROP 1 LAST PATH I76
J 0
(3375 -325);
DISPLAY 1.319149 (3375 -325);
PAINT ORANGE (3375 -325);
DISPLAY INVISIBLE (3375 -325);
FORCEPROP 2 LAST CDS_LOCATION C9L12
J 0
(3375 -375);
DISPLAY 0.617021 (3375 -375);
PAINT AQUA (3375 -375);
DISPLAY INVISIBLE (3375 -375);
FORCEPROP 2 LAST SEC 1
J 0
(3375 -250);
DISPLAY 0.680851 (3375 -250);
PAINT MONO (3375 -250);
DISPLAY INVISIBLE (3375 -250);
FORCEPROP 2 LAST SEC_TYPE 3018
J 0
(3375 -250);
DISPLAY 1.021277 (3375 -250);
PAINT ORANGE (3375 -250);
DISPLAY INVISIBLE (3375 -250);
FORCEADD CAPP..1
(3750 -475);
FORCEPROP 1 LAST PART_NUMBER 699013-049
J 0
(3800 -675);
DISPLAY 0.617021 (3800 -675);
PAINT BLUE (3800 -675);
FORCEPROP 1 LAST PACK_TYPE 3018
J 0
(3800 -625);
DISPLAY 0.617021 (3800 -625);
PAINT SKYBLUE (3800 -625);
FORCEPROP 1 LAST MATERIAL ALUM
J 0
(3800 -575);
DISPLAY 0.617021 (3800 -575);
PAINT SKYBLUE (3800 -575);
FORCEPROP 1 LASTPIN (3750 -575) $PN 2
J 0
(3760 -590);
DISPLAY 0.617021 (3760 -590);
PAINT ORANGE (3760 -590);
FORCEPROP 1 LAST VOLTAGE 2.5V
J 0
(3800 -525);
DISPLAY 0.617021 (3800 -525);
PAINT SKYBLUE (3800 -525);
FORCEPROP 1 LASTPIN (3750 -375) $PN 1
J 0
(3760 -390);
DISPLAY 0.617021 (3760 -390);
PAINT ORANGE (3760 -390);
FORCEPROP 1 LAST LOCATION C9L4
J 0
(3800 -375);
DISPLAY 0.617021 (3800 -375);
PAINT AQUA (3800 -375);
FORCEPROP 1 LAST VALUE 470UF
J 0
(3800 -425);
DISPLAY 0.617021 (3800 -425);
PAINT SKYBLUE (3800 -425);
FORCEPROP 1 LAST TOLERANCE 20%
J 0
(3800 -475);
DISPLAY 0.617021 (3800 -475);
PAINT SKYBLUE (3800 -475);
FORCEPROP 2 LAST CDS_LIB mstr_discrete
J 0
(3750 -475);
PAINT ORANGE (3750 -475);
DISPLAY INVISIBLE (3750 -475);
FORCEPROP 2 LAST CDS_LOCATION C9L4
J 0
(3800 -375);
DISPLAY 0.617021 (3800 -375);
PAINT AQUA (3800 -375);
DISPLAY INVISIBLE (3800 -375);
FORCEPROP 1 LAST PATH I77
J 0
(3800 -325);
DISPLAY 1.319149 (3800 -325);
PAINT ORANGE (3800 -325);
DISPLAY INVISIBLE (3800 -325);
FORCEPROP 0 LAST ROOM VDDQ_KLM_PWR_VR
J 0
(3800 -325);
DISPLAY 1.021277 (3800 -325);
PAINT ORANGE (3800 -325);
DISPLAY INVISIBLE (3800 -325);
FORCEPROP 2 LAST SEC_TYPE 3018
J 0
(3800 -250);
DISPLAY 1.021277 (3800 -250);
PAINT ORANGE (3800 -250);
DISPLAY INVISIBLE (3800 -250);
FORCEPROP 2 LAST SEC 1
J 0
(3800 -250);
DISPLAY 0.680851 (3800 -250);
PAINT MONO (3800 -250);
DISPLAY INVISIBLE (3800 -250);
FORCEADD CAPP..1
(4150 -500);
FORCEPROP 1 LASTPIN (4150 -600) $PN 2
J 0
(4160 -615);
DISPLAY 0.617021 (4160 -615);
PAINT ORANGE (4160 -615);
FORCEPROP 1 LAST MATERIAL ALUM
J 0
(4200 -600);
DISPLAY 0.617021 (4200 -600);
PAINT SKYBLUE (4200 -600);
FORCEPROP 1 LAST VOLTAGE 2.5V
J 0
(4200 -550);
DISPLAY 0.617021 (4200 -550);
PAINT SKYBLUE (4200 -550);
FORCEPROP 1 LAST PACK_TYPE 3018
J 0
(4200 -650);
DISPLAY 0.617021 (4200 -650);
PAINT SKYBLUE (4200 -650);
FORCEPROP 1 LAST PART_NUMBER 699013-049
J 0
(4200 -700);
DISPLAY 0.617021 (4200 -700);
PAINT BLUE (4200 -700);
FORCEPROP 1 LASTPIN (4150 -400) $PN 1
J 0
(4160 -415);
DISPLAY 0.617021 (4160 -415);
PAINT ORANGE (4160 -415);
FORCEPROP 1 LAST LOCATION C9L2
J 0
(4200 -400);
DISPLAY 0.617021 (4200 -400);
PAINT AQUA (4200 -400);
FORCEPROP 1 LAST VALUE 470UF
J 0
(4200 -450);
DISPLAY 0.617021 (4200 -450);
PAINT SKYBLUE (4200 -450);
FORCEPROP 1 LAST TOLERANCE 20%
J 0
(4200 -500);
DISPLAY 0.617021 (4200 -500);
PAINT SKYBLUE (4200 -500);
FORCEPROP 2 LAST CDS_LIB mstr_discrete
J 0
(4150 -500);
PAINT ORANGE (4150 -500);
DISPLAY INVISIBLE (4150 -500);
FORCEPROP 2 LAST CDS_LOCATION C9L2
J 0
(4200 -400);
DISPLAY 0.617021 (4200 -400);
PAINT AQUA (4200 -400);
DISPLAY INVISIBLE (4200 -400);
FORCEPROP 1 LAST PATH I78
J 0
(4200 -350);
DISPLAY 1.319149 (4200 -350);
PAINT ORANGE (4200 -350);
DISPLAY INVISIBLE (4200 -350);
FORCEPROP 0 LAST ROOM VDDQ_KLM_PWR_VR
J 0
(4200 -350);
DISPLAY 1.021277 (4200 -350);
PAINT ORANGE (4200 -350);
DISPLAY INVISIBLE (4200 -350);
FORCEPROP 2 LAST SEC_TYPE 3018
J 0
(4200 -275);
DISPLAY 1.021277 (4200 -275);
PAINT ORANGE (4200 -275);
DISPLAY INVISIBLE (4200 -275);
FORCEPROP 2 LAST SEC 1
J 0
(4200 -275);
DISPLAY 0.680851 (4200 -275);
PAINT MONO (4200 -275);
DISPLAY INVISIBLE (4200 -275);
FORCEADD PVDDQ_KLM..1
(2900 -175);
FORCEPROP 3 LASTPIN (2900 -225) SIG_NAME PVDDQ_KLM\g
J 0
(2910 -215);
DISPLAY 0.659574 (2910 -215);
PAINT MONO (2910 -215);
DISPLAY INVISIBLE (2910 -215);
FORCEPROP 1 LAST VOLTAGE 1.2V
J 0
(2855 -218);
DISPLAY 0.340426 (2855 -218);
PAINT SKYBLUE (2855 -218);
DISPLAY INVISIBLE (2855 -218);
FORCEPROP 2 LAST BOM_COST MEM_VRD_PVPP_AB
J 0
(2950 -75);
PAINT MONO (2950 -75);
DISPLAY INVISIBLE (2950 -75);
FORCEPROP 2 LAST CDS_LIB mstr_symbols
J 0
(2900 -175);
PAINT ORANGE (2900 -175);
DISPLAY INVISIBLE (2900 -175);
FORCEPROP 1 LAST PATH I80
J 0
(2950 -150);
DISPLAY 0.872340 (2950 -150);
PAINT AQUA (2950 -150);
DISPLAY INVISIBLE (2950 -150);
FORCEPROP 2 LAST ROOM VDDQ_KLM_PWR_VR
J 0
(3125 -75);
PAINT ORANGE (3125 -75);
DISPLAY INVISIBLE (3125 -75);
FORCEPROP 1 LAST BODY_TYPE PLUMBING
J 0
(2855 -218);
DISPLAY 0.340426 (2855 -218);
PAINT GREEN (2855 -218);
DISPLAY INVISIBLE (2855 -218);
FORCEPROP 1 LAST HDL_POWER PVDDQ_KLM
J 1
(2900 -125);
DISPLAY 0.872340 (2900 -125);
PAINT GREEN (2900 -125);
DISPLAY INVISIBLE (2900 -125);
FORCEADD GND..1
(2900 -900);
FORCEPROP 3 LASTPIN (2900 -850) SIG_NAME GND\g
J 0
(2910 -840);
DISPLAY 0.659574 (2910 -840);
PAINT MONO (2910 -840);
DISPLAY INVISIBLE (2910 -840);
FORCEPROP 2 LAST BOM_COST MEM_VRD_PVPP_AB
J 0
(2575 -825);
PAINT MONO (2575 -825);
DISPLAY INVISIBLE (2575 -825);
FORCEPROP 1 LAST VOLTAGE 0
J 0
(2900 -900);
PAINT SKYBLUE (2900 -900);
DISPLAY INVISIBLE (2900 -900);
FORCEPROP 1 LAST SIZE 1B
J 0
(2975 -950);
DISPLAY 0.893617 (2975 -950);
PAINT GREEN (2975 -950);
DISPLAY INVISIBLE (2975 -950);
FORCEPROP 2 LAST CDS_LIB mstr_symbols
J 0
(2900 -900);
PAINT ORANGE (2900 -900);
DISPLAY INVISIBLE (2900 -900);
FORCEPROP 1 LAST PATH I81
J 0
(2975 -900);
DISPLAY 1.170213 (2975 -900);
PAINT AQUA (2975 -900);
DISPLAY INVISIBLE (2975 -900);
FORCEPROP 1 LAST BODY_TYPE PLUMBING
J 0
(2855 -943);
DISPLAY 0.340426 (2855 -943);
PAINT GREEN (2855 -943);
DISPLAY INVISIBLE (2855 -943);
FORCEPROP 1 LAST HDL_POWER GND
J 0
(2900 -750);
DISPLAY 0.893617 (2900 -750);
PAINT GREEN (2900 -750);
DISPLAY INVISIBLE (2900 -750);
FORCEADD CAP..1
(5000 2825);
FORCEPROP 1 LASTPIN (5000 2725) $PN 2
J 0
(5010 2705);
DISPLAY 0.617021 (5010 2705);
PAINT ORANGE (5010 2705);
FORCEPROP 1 LASTPIN (5000 2925) $PN 1
J 0
(5010 2905);
DISPLAY 0.617021 (5010 2905);
PAINT ORANGE (5010 2905);
FORCEPROP 1 LAST VOLTAGE 4V
J 0
(5050 2825);
DISPLAY 0.617021 (5050 2825);
PAINT SKYBLUE (5050 2825);
FORCEPROP 1 LAST LOCATION C2A8
J 0
(5050 2925);
DISPLAY 0.617021 (5050 2925);
PAINT AQUA (5050 2925);
FORCEPROP 1 LAST PART_NUMBER 602433-112
J 0
(5050 2675);
DISPLAY 0.617021 (5050 2675);
PAINT BLUE (5050 2675);
FORCEPROP 1 LAST VALUE 100UF
J 0
(5050 2875);
DISPLAY 0.617021 (5050 2875);
PAINT SKYBLUE (5050 2875);
FORCEPROP 1 LAST TOLERANCE 20%
J 0
(5050 2775);
DISPLAY 0.617021 (5050 2775);
PAINT SKYBLUE (5050 2775);
FORCEPROP 1 LAST PACK_TYPE 0805
J 0
(5050 2625);
DISPLAY 0.617021 (5050 2625);
PAINT SKYBLUE (5050 2625);
FORCEPROP 1 LAST MATERIAL X5R
J 0
(5050 2725);
DISPLAY 0.617021 (5050 2725);
PAINT SKYBLUE (5050 2725);
FORCEPROP 2 LAST CDS_LIB mstr_discrete
J 0
(5000 2825);
PAINT MONO (5000 2825);
DISPLAY INVISIBLE (5000 2825);
FORCEPROP 2 LAST CDS_LOCATION C2A8
J 0
(5050 2925);
DISPLAY 0.617021 (5050 2925);
PAINT AQUA (5050 2925);
DISPLAY INVISIBLE (5050 2925);
FORCEPROP 2 LAST SEC 1
J 0
(5050 3025);
DISPLAY 0.680851 (5050 3025);
PAINT MONO (5050 3025);
DISPLAY INVISIBLE (5050 3025);
FORCEPROP 2 LAST BOM_COST MEM_VRD_PVDDQ_CD
J 0
(5050 2975);
PAINT MONO (5050 2975);
DISPLAY INVISIBLE (5050 2975);
FORCEPROP 2 LAST SEC_TYPE 0805
J 0
(5050 3025);
DISPLAY 1.021277 (5050 3025);
PAINT ORANGE (5050 3025);
DISPLAY INVISIBLE (5050 3025);
FORCEPROP 1 LAST PATH I82
J 0
(5050 2975);
DISPLAY 0.978723 (5050 2975);
PAINT WHITE (5050 2975);
DISPLAY INVISIBLE (5050 2975);
FORCEPROP 2 LAST ROOM VDDQ_KLM_PWR_VR
J 0
(5050 2975);
PAINT MONO (5050 2975);
DISPLAY INVISIBLE (5050 2975);
FORCEADD CAP..1
(4600 2825);
FORCEPROP 1 LAST LOCATION C8L2
J 0
(4650 2925);
DISPLAY 0.617021 (4650 2925);
PAINT AQUA (4650 2925);
FORCEPROP 1 LAST VALUE 100UF
J 0
(4650 2875);
DISPLAY 0.617021 (4650 2875);
PAINT SKYBLUE (4650 2875);
FORCEPROP 1 LAST TOLERANCE 20%
J 0
(4650 2775);
DISPLAY 0.617021 (4650 2775);
PAINT SKYBLUE (4650 2775);
FORCEPROP 1 LAST PACK_TYPE 0805
J 0
(4650 2625);
DISPLAY 0.617021 (4650 2625);
PAINT SKYBLUE (4650 2625);
FORCEPROP 1 LAST VOLTAGE 4V
J 0
(4650 2825);
DISPLAY 0.617021 (4650 2825);
PAINT SKYBLUE (4650 2825);
FORCEPROP 1 LAST MATERIAL X5R
J 0
(4650 2725);
DISPLAY 0.617021 (4650 2725);
PAINT SKYBLUE (4650 2725);
FORCEPROP 1 LASTPIN (4600 2725) $PN 2
J 0
(4610 2705);
DISPLAY 0.617021 (4610 2705);
PAINT ORANGE (4610 2705);
FORCEPROP 1 LASTPIN (4600 2925) $PN 1
J 0
(4610 2905);
DISPLAY 0.617021 (4610 2905);
PAINT ORANGE (4610 2905);
FORCEPROP 1 LAST PART_NUMBER 602433-112
J 0
(4650 2675);
DISPLAY 0.617021 (4650 2675);
PAINT BLUE (4650 2675);
FORCEPROP 2 LAST CDS_LIB mstr_discrete
J 0
(4600 2825);
PAINT MONO (4600 2825);
DISPLAY INVISIBLE (4600 2825);
FORCEPROP 2 LAST BOM_COST MEM_VRD_PVDDQ_CD
J 0
(4650 2975);
PAINT MONO (4650 2975);
DISPLAY INVISIBLE (4650 2975);
FORCEPROP 2 LAST SEC_TYPE 0805
J 0
(4650 3025);
DISPLAY 1.021277 (4650 3025);
PAINT ORANGE (4650 3025);
DISPLAY INVISIBLE (4650 3025);
FORCEPROP 2 LAST SEC 1
J 0
(4650 3025);
DISPLAY 0.680851 (4650 3025);
PAINT MONO (4650 3025);
DISPLAY INVISIBLE (4650 3025);
FORCEPROP 2 LAST CDS_LOCATION C8L2
J 0
(4650 2925);
DISPLAY 0.617021 (4650 2925);
PAINT AQUA (4650 2925);
DISPLAY INVISIBLE (4650 2925);
FORCEPROP 1 LAST PATH I83
J 0
(4650 2975);
DISPLAY 0.978723 (4650 2975);
PAINT WHITE (4650 2975);
DISPLAY INVISIBLE (4650 2975);
FORCEPROP 2 LAST ROOM VDDQ_KLM_PWR_VR
J 0
(4650 2975);
PAINT MONO (4650 2975);
DISPLAY INVISIBLE (4650 2975);
FORCEADD CAP..1
(4250 2825);
FORCEPROP 1 LASTPIN (4250 2725) $PN 2
J 0
(4260 2705);
DISPLAY 0.617021 (4260 2705);
PAINT ORANGE (4260 2705);
FORCEPROP 1 LASTPIN (4250 2925) $PN 1
J 0
(4260 2905);
DISPLAY 0.617021 (4260 2905);
PAINT ORANGE (4260 2905);
FORCEPROP 1 LAST LOCATION C8L11
J 0
(4300 2925);
DISPLAY 0.617021 (4300 2925);
PAINT AQUA (4300 2925);
FORCEPROP 1 LAST PART_NUMBER 602433-112
J 0
(4300 2675);
DISPLAY 0.617021 (4300 2675);
PAINT BLUE (4300 2675);
FORCEPROP 1 LAST VALUE 100UF
J 0
(4300 2875);
DISPLAY 0.617021 (4300 2875);
PAINT SKYBLUE (4300 2875);
FORCEPROP 1 LAST TOLERANCE 20%
J 0
(4300 2775);
DISPLAY 0.617021 (4300 2775);
PAINT SKYBLUE (4300 2775);
FORCEPROP 1 LAST PACK_TYPE 0805
J 0
(4300 2625);
DISPLAY 0.617021 (4300 2625);
PAINT SKYBLUE (4300 2625);
FORCEPROP 1 LAST VOLTAGE 4V
J 0
(4300 2825);
DISPLAY 0.617021 (4300 2825);
PAINT SKYBLUE (4300 2825);
FORCEPROP 1 LAST MATERIAL X5R
J 0
(4300 2725);
DISPLAY 0.617021 (4300 2725);
PAINT SKYBLUE (4300 2725);
FORCEPROP 2 LAST CDS_LIB mstr_discrete
J 0
(4250 2825);
PAINT MONO (4250 2825);
DISPLAY INVISIBLE (4250 2825);
FORCEPROP 2 LAST CDS_LOCATION C8L11
J 0
(4300 2925);
DISPLAY 0.617021 (4300 2925);
PAINT AQUA (4300 2925);
DISPLAY INVISIBLE (4300 2925);
FORCEPROP 2 LAST SEC 1
J 0
(4300 3025);
DISPLAY 0.680851 (4300 3025);
PAINT MONO (4300 3025);
DISPLAY INVISIBLE (4300 3025);
FORCEPROP 2 LAST SEC_TYPE 0805
J 0
(4300 3025);
DISPLAY 1.021277 (4300 3025);
PAINT ORANGE (4300 3025);
DISPLAY INVISIBLE (4300 3025);
FORCEPROP 2 LAST BOM_COST MEM_VRD_PVDDQ_CD
J 0
(4300 2975);
PAINT MONO (4300 2975);
DISPLAY INVISIBLE (4300 2975);
FORCEPROP 1 LAST PATH I88
J 0
(4300 2975);
DISPLAY 0.978723 (4300 2975);
PAINT WHITE (4300 2975);
DISPLAY INVISIBLE (4300 2975);
FORCEPROP 2 LAST ROOM VDDQ_KLM_PWR_VR
J 0
(4300 2975);
PAINT MONO (4300 2975);
DISPLAY INVISIBLE (4300 2975);
FORCEADD CAP..1
(3850 2825);
FORCEPROP 1 LAST MATERIAL X5R
J 0
(3900 2725);
DISPLAY 0.617021 (3900 2725);
PAINT SKYBLUE (3900 2725);
FORCEPROP 1 LAST PACK_TYPE 0805
J 0
(3900 2625);
DISPLAY 0.617021 (3900 2625);
PAINT SKYBLUE (3900 2625);
FORCEPROP 1 LAST TOLERANCE 20%
J 0
(3900 2775);
DISPLAY 0.617021 (3900 2775);
PAINT SKYBLUE (3900 2775);
FORCEPROP 1 LASTPIN (3850 2725) $PN 2
J 0
(3860 2705);
DISPLAY 0.617021 (3860 2705);
PAINT ORANGE (3860 2705);
FORCEPROP 1 LAST VOLTAGE 4V
J 0
(3900 2825);
DISPLAY 0.617021 (3900 2825);
PAINT SKYBLUE (3900 2825);
FORCEPROP 1 LASTPIN (3850 2925) $PN 1
J 0
(3860 2905);
DISPLAY 0.617021 (3860 2905);
PAINT ORANGE (3860 2905);
FORCEPROP 1 LAST LOCATION C2A16
J 0
(3900 2925);
DISPLAY 0.617021 (3900 2925);
PAINT AQUA (3900 2925);
FORCEPROP 1 LAST VALUE 100UF
J 0
(3900 2875);
DISPLAY 0.617021 (3900 2875);
PAINT SKYBLUE (3900 2875);
FORCEPROP 1 LAST PART_NUMBER 602433-112
J 0
(3900 2675);
DISPLAY 0.617021 (3900 2675);
PAINT BLUE (3900 2675);
FORCEPROP 2 LAST CDS_LIB mstr_discrete
J 0
(3850 2825);
PAINT MONO (3850 2825);
DISPLAY INVISIBLE (3850 2825);
FORCEPROP 2 LAST CDS_LOCATION C2A16
J 0
(3900 2925);
DISPLAY 0.617021 (3900 2925);
PAINT AQUA (3900 2925);
DISPLAY INVISIBLE (3900 2925);
FORCEPROP 2 LAST SEC_TYPE 0805
J 0
(3900 3025);
DISPLAY 1.021277 (3900 3025);
PAINT ORANGE (3900 3025);
DISPLAY INVISIBLE (3900 3025);
FORCEPROP 2 LAST BOM_COST MEM_VRD_PVDDQ_CD
J 0
(3900 2975);
PAINT MONO (3900 2975);
DISPLAY INVISIBLE (3900 2975);
FORCEPROP 2 LAST SEC 1
J 0
(3900 3025);
DISPLAY 0.680851 (3900 3025);
PAINT MONO (3900 3025);
DISPLAY INVISIBLE (3900 3025);
FORCEPROP 1 LAST PATH I89
J 0
(3900 2975);
DISPLAY 0.978723 (3900 2975);
PAINT WHITE (3900 2975);
DISPLAY INVISIBLE (3900 2975);
FORCEPROP 2 LAST ROOM VDDQ_KLM_PWR_VR
J 0
(3900 2975);
PAINT MONO (3900 2975);
DISPLAY INVISIBLE (3900 2975);
FORCEADD CAP..1
(3500 2825);
FORCEPROP 1 LASTPIN (3500 2725) $PN 2
J 0
(3510 2705);
DISPLAY 0.617021 (3510 2705);
PAINT ORANGE (3510 2705);
FORCEPROP 1 LASTPIN (3500 2925) $PN 1
J 0
(3510 2905);
DISPLAY 0.617021 (3510 2905);
PAINT ORANGE (3510 2905);
FORCEPROP 1 LAST LOCATION C8M7
J 0
(3550 2925);
DISPLAY 0.617021 (3550 2925);
PAINT AQUA (3550 2925);
FORCEPROP 1 LAST PART_NUMBER 602433-112
J 0
(3550 2675);
DISPLAY 0.617021 (3550 2675);
PAINT BLUE (3550 2675);
FORCEPROP 1 LAST VALUE 100UF
J 0
(3550 2875);
DISPLAY 0.617021 (3550 2875);
PAINT SKYBLUE (3550 2875);
FORCEPROP 1 LAST TOLERANCE 20%
J 0
(3550 2775);
DISPLAY 0.617021 (3550 2775);
PAINT SKYBLUE (3550 2775);
FORCEPROP 1 LAST PACK_TYPE 0805
J 0
(3550 2625);
DISPLAY 0.617021 (3550 2625);
PAINT SKYBLUE (3550 2625);
FORCEPROP 1 LAST VOLTAGE 4V
J 0
(3550 2825);
DISPLAY 0.617021 (3550 2825);
PAINT SKYBLUE (3550 2825);
FORCEPROP 1 LAST MATERIAL X5R
J 0
(3550 2725);
DISPLAY 0.617021 (3550 2725);
PAINT SKYBLUE (3550 2725);
FORCEPROP 2 LAST CDS_LIB mstr_discrete
J 0
(3500 2825);
PAINT MONO (3500 2825);
DISPLAY INVISIBLE (3500 2825);
FORCEPROP 2 LAST CDS_LOCATION C8M7
J 0
(3550 2925);
DISPLAY 0.617021 (3550 2925);
PAINT AQUA (3550 2925);
DISPLAY INVISIBLE (3550 2925);
FORCEPROP 1 LAST PATH I90
J 0
(3550 2975);
DISPLAY 0.978723 (3550 2975);
PAINT WHITE (3550 2975);
DISPLAY INVISIBLE (3550 2975);
FORCEPROP 2 LAST SEC 1
J 0
(3550 3025);
DISPLAY 0.680851 (3550 3025);
PAINT MONO (3550 3025);
DISPLAY INVISIBLE (3550 3025);
FORCEPROP 2 LAST BOM_COST MEM_VRD_PVDDQ_CD
J 0
(3550 2975);
PAINT MONO (3550 2975);
DISPLAY INVISIBLE (3550 2975);
FORCEPROP 2 LAST SEC_TYPE 0805
J 0
(3550 3025);
DISPLAY 1.021277 (3550 3025);
PAINT ORANGE (3550 3025);
DISPLAY INVISIBLE (3550 3025);
FORCEPROP 2 LAST ROOM VDDQ_KLM_PWR_VR
J 0
(3550 2975);
PAINT MONO (3550 2975);
DISPLAY INVISIBLE (3550 2975);
FORCEADD CAP..1
(3150 2825);
FORCEPROP 1 LASTPIN (3150 2725) $PN 2
J 0
(3160 2705);
DISPLAY 0.617021 (3160 2705);
PAINT ORANGE (3160 2705);
FORCEPROP 1 LAST MATERIAL X5R
J 0
(3200 2725);
DISPLAY 0.617021 (3200 2725);
PAINT SKYBLUE (3200 2725);
FORCEPROP 1 LAST PACK_TYPE 0805
J 0
(3200 2625);
DISPLAY 0.617021 (3200 2625);
PAINT SKYBLUE (3200 2625);
FORCEPROP 1 LAST TOLERANCE 20%
J 0
(3200 2775);
DISPLAY 0.617021 (3200 2775);
PAINT SKYBLUE (3200 2775);
FORCEPROP 1 LASTPIN (3150 2925) $PN 1
J 0
(3160 2905);
DISPLAY 0.617021 (3160 2905);
PAINT ORANGE (3160 2905);
FORCEPROP 1 LAST VOLTAGE 4V
J 0
(3200 2825);
DISPLAY 0.617021 (3200 2825);
PAINT SKYBLUE (3200 2825);
FORCEPROP 1 LAST LOCATION C8M11
J 0
(3200 2925);
DISPLAY 0.617021 (3200 2925);
PAINT AQUA (3200 2925);
FORCEPROP 1 LAST PART_NUMBER 602433-112
J 0
(3200 2675);
DISPLAY 0.617021 (3200 2675);
PAINT BLUE (3200 2675);
FORCEPROP 1 LAST VALUE 100UF
J 0
(3200 2875);
DISPLAY 0.617021 (3200 2875);
PAINT SKYBLUE (3200 2875);
FORCEPROP 2 LAST CDS_LIB mstr_discrete
J 0
(3150 2825);
PAINT MONO (3150 2825);
DISPLAY INVISIBLE (3150 2825);
FORCEPROP 2 LAST ROOM VDDQ_KLM_PWR_VR
J 0
(3200 2975);
PAINT MONO (3200 2975);
DISPLAY INVISIBLE (3200 2975);
FORCEPROP 1 LAST PATH I91
J 0
(3200 2975);
DISPLAY 0.978723 (3200 2975);
PAINT WHITE (3200 2975);
DISPLAY INVISIBLE (3200 2975);
FORCEPROP 2 LAST CDS_LOCATION C8M11
J 0
(3200 2925);
DISPLAY 0.617021 (3200 2925);
PAINT AQUA (3200 2925);
DISPLAY INVISIBLE (3200 2925);
FORCEPROP 2 LAST SEC 1
J 0
(3200 3025);
DISPLAY 0.680851 (3200 3025);
PAINT MONO (3200 3025);
DISPLAY INVISIBLE (3200 3025);
FORCEPROP 2 LAST BOM_COST MEM_VRD_PVDDQ_CD
J 0
(3200 2975);
PAINT MONO (3200 2975);
DISPLAY INVISIBLE (3200 2975);
FORCEPROP 2 LAST SEC_TYPE 0805
J 0
(3200 3025);
DISPLAY 1.021277 (3200 3025);
PAINT ORANGE (3200 3025);
DISPLAY INVISIBLE (3200 3025);
FORCEADD CAP..1
(2750 2825);
FORCEPROP 1 LASTPIN (2750 2725) $PN 2
J 0
(2760 2705);
DISPLAY 0.617021 (2760 2705);
PAINT ORANGE (2760 2705);
FORCEPROP 1 LASTPIN (2750 2925) $PN 1
J 0
(2760 2905);
DISPLAY 0.617021 (2760 2905);
PAINT ORANGE (2760 2905);
FORCEPROP 1 LAST LOCATION C7L1
J 0
(2800 2925);
DISPLAY 0.617021 (2800 2925);
PAINT AQUA (2800 2925);
FORCEPROP 1 LAST VALUE 100UF
J 0
(2800 2875);
DISPLAY 0.617021 (2800 2875);
PAINT SKYBLUE (2800 2875);
FORCEPROP 1 LAST TOLERANCE 20%
J 0
(2800 2775);
DISPLAY 0.617021 (2800 2775);
PAINT SKYBLUE (2800 2775);
FORCEPROP 1 LAST PACK_TYPE 0805
J 0
(2800 2625);
DISPLAY 0.617021 (2800 2625);
PAINT SKYBLUE (2800 2625);
FORCEPROP 1 LAST VOLTAGE 4V
J 0
(2800 2825);
DISPLAY 0.617021 (2800 2825);
PAINT SKYBLUE (2800 2825);
FORCEPROP 1 LAST MATERIAL X5R
J 0
(2800 2725);
DISPLAY 0.617021 (2800 2725);
PAINT SKYBLUE (2800 2725);
FORCEPROP 1 LAST PART_NUMBER 602433-112
J 0
(2800 2675);
DISPLAY 0.617021 (2800 2675);
PAINT BLUE (2800 2675);
FORCEPROP 2 LAST CDS_LIB mstr_discrete
J 0
(2750 2825);
PAINT MONO (2750 2825);
DISPLAY INVISIBLE (2750 2825);
FORCEPROP 2 LAST CDS_LOCATION C7L1
J 0
(2800 2925);
DISPLAY 0.617021 (2800 2925);
PAINT AQUA (2800 2925);
DISPLAY INVISIBLE (2800 2925);
FORCEPROP 1 LAST PATH I92
J 0
(2800 2975);
DISPLAY 0.978723 (2800 2975);
PAINT WHITE (2800 2975);
DISPLAY INVISIBLE (2800 2975);
FORCEPROP 2 LAST SEC 1
J 0
(2800 3025);
DISPLAY 0.680851 (2800 3025);
PAINT MONO (2800 3025);
DISPLAY INVISIBLE (2800 3025);
FORCEPROP 2 LAST BOM_COST MEM_VRD_PVDDQ_CD
J 0
(2800 2975);
PAINT MONO (2800 2975);
DISPLAY INVISIBLE (2800 2975);
FORCEPROP 2 LAST SEC_TYPE 0805
J 0
(2800 3025);
DISPLAY 1.021277 (2800 3025);
PAINT ORANGE (2800 3025);
DISPLAY INVISIBLE (2800 3025);
FORCEPROP 2 LAST ROOM VDDQ_KLM_PWR_VR
J 0
(2800 2975);
PAINT MONO (2800 2975);
DISPLAY INVISIBLE (2800 2975);
FORCEADD PVDDQ_KLM..1
(2400 3100);
FORCEPROP 3 LASTPIN (2400 3050) SIG_NAME PVDDQ_KLM\g
J 0
(2410 3060);
DISPLAY 0.659574 (2410 3060);
PAINT MONO (2410 3060);
DISPLAY INVISIBLE (2410 3060);
FORCEPROP 1 LAST VOLTAGE 1.2V
J 0
(2355 3057);
DISPLAY 0.340426 (2355 3057);
PAINT SKYBLUE (2355 3057);
DISPLAY INVISIBLE (2355 3057);
FORCEPROP 2 LAST BOM_COST MEM_VRD_PVDDQ_CD
J 0
(2475 3200);
PAINT MONO (2475 3200);
DISPLAY INVISIBLE (2475 3200);
FORCEPROP 2 LAST CDS_LIB mstr_symbols
J 0
(2400 3100);
PAINT ORANGE (2400 3100);
DISPLAY INVISIBLE (2400 3100);
FORCEPROP 1 LAST PATH I93
J 0
(2450 3125);
DISPLAY 0.872340 (2450 3125);
PAINT AQUA (2450 3125);
DISPLAY INVISIBLE (2450 3125);
FORCEPROP 2 LAST ROOM VDDQ_KLM_PWR_VR
J 0
(2650 3200);
PAINT ORANGE (2650 3200);
DISPLAY INVISIBLE (2650 3200);
FORCEPROP 1 LAST BODY_TYPE PLUMBING
J 0
(2355 3057);
DISPLAY 0.340426 (2355 3057);
PAINT GREEN (2355 3057);
DISPLAY INVISIBLE (2355 3057);
FORCEPROP 1 LAST HDL_POWER PVDDQ_KLM
J 1
(2400 3150);
DISPLAY 0.872340 (2400 3150);
PAINT GREEN (2400 3150);
DISPLAY INVISIBLE (2400 3150);
FORCEADD GND..1
(4125 2450);
FORCEPROP 3 LASTPIN (4125 2500) SIG_NAME GND\g
J 0
(4135 2510);
DISPLAY 0.659574 (4135 2510);
PAINT MONO (4135 2510);
DISPLAY INVISIBLE (4135 2510);
FORCEPROP 2 LAST ROOM VDDQ_KLM_PWR_VR
J 0
(3575 2525);
PAINT ORANGE (3575 2525);
DISPLAY INVISIBLE (3575 2525);
FORCEPROP 2 LAST BOM_COST MEM_VRD_PVDDQ_CD
J 0
(3800 2525);
PAINT MONO (3800 2525);
DISPLAY INVISIBLE (3800 2525);
FORCEPROP 1 LAST VOLTAGE 0
J 0
(4125 2450);
PAINT SKYBLUE (4125 2450);
DISPLAY INVISIBLE (4125 2450);
FORCEPROP 1 LAST SIZE 1B
J 0
(4200 2400);
DISPLAY 0.893617 (4200 2400);
PAINT GREEN (4200 2400);
DISPLAY INVISIBLE (4200 2400);
FORCEPROP 2 LAST CDS_LIB mstr_symbols
J 0
(4125 2450);
PAINT ORANGE (4125 2450);
DISPLAY INVISIBLE (4125 2450);
FORCEPROP 1 LAST PATH I94
J 0
(4200 2450);
DISPLAY 1.170213 (4200 2450);
PAINT AQUA (4200 2450);
DISPLAY INVISIBLE (4200 2450);
FORCEPROP 1 LAST BODY_TYPE PLUMBING
J 0
(4080 2407);
DISPLAY 0.340426 (4080 2407);
PAINT GREEN (4080 2407);
DISPLAY INVISIBLE (4080 2407);
FORCEPROP 1 LAST HDL_POWER GND
J 0
(4125 2600);
DISPLAY 0.893617 (4125 2600);
PAINT GREEN (4125 2600);
DISPLAY INVISIBLE (4125 2600);
FORCEADD DNS..2
(-370 1920);
PAINT RED (-370 1920);
FORCEPROP 2 LAST CDS_LIB mstr_misc
J 0
(-370 1920);
PAINT ORANGE (-370 1920);
DISPLAY INVISIBLE (-370 1920);
FORCEPROP 1 LAST COMMENT_BODY TRUE
R 1
J 0
(-295 1695);
DISPLAY 0.872340 (-295 1695);
PAINT GREEN (-295 1695);
DISPLAY INVISIBLE (-295 1695);
FORCEADD DNS..3
(80 2170);
PAINT RED (80 2170);
FORCEPROP 2 LAST CDS_LIB mstr_misc
J 0
(80 2170);
PAINT ORANGE (80 2170);
DISPLAY INVISIBLE (80 2170);
FORCEPROP 1 LAST COMMENT_BODY TRUE
R 1
J 0
(155 1945);
DISPLAY 0.872340 (155 1945);
PAINT GREEN (155 1945);
DISPLAY INVISIBLE (155 1945);
FORCEADD DNS..3
(80 1720);
PAINT RED (80 1720);
FORCEPROP 2 LAST CDS_LIB mstr_misc
J 0
(80 1720);
PAINT ORANGE (80 1720);
DISPLAY INVISIBLE (80 1720);
FORCEPROP 1 LAST COMMENT_BODY TRUE
R 1
J 0
(155 1495);
DISPLAY 0.872340 (155 1495);
PAINT GREEN (155 1495);
DISPLAY INVISIBLE (155 1495);
FORCEADD INTEL_CORP_BPAGE..1
(5475 -1550);
FORCEPROP 1 LAST CDS_CON_LAST_MODIFIED Tue Dec 01 11:52:28 2015
J 0
(4050 -1225);
PAINT GREEN (4050 -1225);
DISPLAY INVISIBLE (4050 -1225);
FORCEPROP 1 LAST CUSTOM_TXT_CDS <CURRENT_DESIGN_SHEET> OF <TOTAL_DESIGN_SHEETS>
J 0
(4975 -1525);
PAINT GREEN (4975 -1525);
FORCEPROP 2 LAST CUSTOM_TXT_CDS <XR_PAGE_TITLE>
J 0
(-2415 3700);
DISPLAY 0.638298 (-2415 3700);
PAINT PINK (-2415 3700);
DISPLAY INVISIBLE (-2415 3700);
FORCEPROP 2 LAST CUSTOM_TXT_CDS <CON_LAST_MODIFIED>
J 0
(4525 -1200);
PAINT GREEN (4525 -1200);
FORCEPROP 2 LAST CUSTOM_TXT_CDS <CON_PAGE_NUM> OF <CON_TOTAL_PAGES>
J 0
(4975 -1525);
PAINT GREEN (4975 -1525);
FORCEPROP 1 LAST SCH_ADDRESS2 P.O. BOX 58119
J 0
(1500 -1475);
DISPLAY 0.617021 (1500 -1475);
PAINT GREEN (1500 -1475);
FORCEPROP 1 LAST SCH_ADDRESS3 Santa Clara, CA 95052-8119
J 0
(1500 -1525);
DISPLAY 0.617021 (1500 -1525);
PAINT GREEN (1500 -1525);
FORCEPROP 1 LAST SCH_ADDRESS1 2200 Mission College Blvd.
J 0
(1500 -1425);
DISPLAY 0.617021 (1500 -1425);
PAINT GREEN (1500 -1425);
FORCEPROP 1 LAST SCH_NUMBER H4694802
J 0
(4175 -1400);
DISPLAY 1.212766 (4175 -1400);
PAINT YELLOW (4175 -1400);
FORCEPROP 1 LAST SCH_DEPT BESD
J 1
(1025 -1450);
DISPLAY 1.212766 (1025 -1450);
PAINT YELLOW (1025 -1450);
FORCEPROP 1 LAST SCH_REV 2.420
J 0
(5225 -1400);
DISPLAY 0.978723 (5225 -1400);
PAINT YELLOW (5225 -1400);
FORCEPROP 1 LAST SCH_TITLE VDDQ KLM DECAP (3 OF 3)
J 0
(-2475 -1500);
DISPLAY 1.212766 (-2475 -1500);
PAINT GREEN (-2475 -1500);
FORCEPROP 2 LAST ROOM VDDQ_KLM_PWR_VR
J 0
(-2625 3550);
PAINT ORANGE (-2625 3550);
DISPLAY INVISIBLE (-2625 3550);
FORCEPROP 2 LAST PAGE_BORDER TRUE
J 0
(-2415 3700);
DISPLAY 0.851064 (-2415 3700);
PAINT PINK (-2415 3700);
DISPLAY INVISIBLE (-2415 3700);
FORCEPROP 2 LAST CDS_LIB mstr_symbols
J 0
(5475 -1550);
PAINT ORANGE (5475 -1550);
DISPLAY INVISIBLE (5475 -1550);
FORCEPROP 1 LAST COMMENT_BODY TRUE
J 0
(5487 -1538);
DISPLAY 0.446809 (5487 -1538);
PAINT GREEN (5487 -1538);
DISPLAY INVISIBLE (5487 -1538);
FORCEPROP 2 LAST CDS_XR_PAGE_TITLE CR-228 : @BASEBOARD_FAB2_LIB.BASEBOARD_FAB2(SCH_1):PAGE228
J 0
(-2415 3700);
DISPLAY 0.638298 (-2415 3700);
PAINT PINK (-2415 3700);
DISPLAY INVISIBLE (-2415 3700);
WIRE 16 -1 (4375 1525)(4375 1600);
WIRE 16 -1 (4375 1600)(3975 1600);
WIRE 16 -1 (3975 1525)(3975 1600);
WIRE 16 -1 (3975 1600)(3625 1600);
WIRE 16 -1 (3625 1525)(3625 1600);
WIRE 16 -1 (3625 1600)(3275 1600);
WIRE 16 -1 (3275 1525)(3275 1600);
WIRE 16 -1 (3275 1600)(2875 1600);
WIRE 16 -1 (2875 1525)(2875 1600);
WIRE 16 -1 (2525 1600)(2875 1600);
WIRE 16 -1 (2525 1600)(2525 1650);
WIRE 16 -1 (2525 1600)(2525 1525);
WIRE 16 -1 (2525 1325)(2525 1175);
WIRE 16 -1 (2525 1175)(2875 1175);
WIRE 16 -1 (2875 1325)(2875 1175);
WIRE 16 -1 (2875 1175)(3275 1175);
WIRE 16 -1 (3275 1325)(3275 1175);
WIRE 16 -1 (3275 1175)(3625 1175);
WIRE 16 -1 (3625 1325)(3625 1175);
WIRE 16 -1 (3625 1175)(3975 1175);
WIRE 16 -1 (3975 1325)(3975 1175);
WIRE 16 -1 (4250 1175)(3975 1175);
WIRE 16 -1 (4250 1175)(4375 1175);
WIRE 16 -1 (4250 1100)(4250 1175);
WIRE 16 -1 (4375 1325)(4375 1175);
WIRE 16 -1 (-1000 1100)(-675 1100);
WIRE 16 -1 (-675 1100)(-675 1300);
WIRE 16 -1 (-675 1000)(-675 1100);
WIRE 16 -1 (-675 800)(-675 725);
WIRE 16 -1 (-1400 1100)(-1200 1100);
WIRE 16 -1 (-1400 1325)(-1400 1100);
WIRE 16 -1 (-1550 2800)(-1550 2650);
WIRE 16 -1 (-1550 2650)(-1200 2650);
WIRE 16 -1 (-1200 2800)(-1200 2650);
WIRE 16 -1 (-1200 2650)(-850 2650);
WIRE 16 -1 (-850 2800)(-850 2650);
WIRE 16 -1 (-850 2650)(-500 2650);
WIRE 16 -1 (-500 2800)(-500 2650);
WIRE 16 -1 (-500 2575)(-500 2650);
WIRE 16 -1 (-1900 3000)(-1900 3075);
WIRE 16 -1 (-2300 3075)(-1900 3075);
WIRE 16 -1 (-2300 3075)(-2300 3125);
WIRE 16 -1 (-2300 3075)(-2300 3000);
WIRE 16 -1 (3300 825)(3300 900);
WIRE 16 -1 (3300 900)(2900 900);
WIRE 16 -1 (2900 825)(2900 900);
WIRE 16 -1 (2550 900)(2900 900);
WIRE 16 -1 (2550 900)(2550 825);
WIRE 16 -1 (2550 900)(2550 950);
WIRE 16 -1 (2550 625)(2550 475);
WIRE 16 -1 (2550 475)(2900 475);
WIRE 16 -1 (2900 625)(2900 475);
WIRE 16 -1 (2900 475)(3300 475);
WIRE 16 -1 (3300 625)(3300 475);
WIRE 16 -1 (3300 375)(3300 475);
WIRE 16 -1 (-500 3000)(-500 3075);
WIRE 16 -1 (-500 3075)(-850 3075);
WIRE 16 -1 (-850 3000)(-850 3075);
WIRE 16 -1 (-850 3075)(-1200 3075);
WIRE 16 -1 (-1200 3000)(-1200 3075);
WIRE 16 -1 (-1200 3075)(-1550 3075);
WIRE 16 -1 (-1550 3000)(-1550 3075);
WIRE 16 -1 (-1550 3075)(-1550 3125);
WIRE 16 -1 (-2300 2800)(-2300 2650);
WIRE 16 -1 (-2300 2650)(-1900 2650);
WIRE 16 -1 (-1900 2800)(-1900 2650);
WIRE 16 -1 (-1900 2575)(-1900 2650);
WIRE 16 -1 (2125 25)(2125 75);
WIRE 16 -1 (2125 75)(1850 75);
WIRE 16 -1 (1850 25)(1850 75);
WIRE 16 -1 (1850 75)(1550 75);
WIRE 16 -1 (1550 25)(1550 75);
WIRE 16 -1 (1550 75)(1250 75);
WIRE 16 -1 (1250 25)(1250 75);
WIRE 16 -1 (1250 75)(975 75);
WIRE 16 -1 (975 25)(975 75);
WIRE 16 -1 (975 75)(700 75);
WIRE 16 -1 (700 25)(700 75);
WIRE 16 -1 (700 75)(400 75);
WIRE 16 -1 (400 25)(400 75);
WIRE 16 -1 (400 75)(100 75);
WIRE 16 -1 (100 25)(100 75);
WIRE 16 -1 (100 75)(-225 75);
WIRE 16 -1 (-225 25)(-225 75);
WIRE 16 -1 (-225 75)(-500 75);
WIRE 16 -1 (-500 25)(-500 75);
WIRE 16 -1 (-500 75)(-800 75);
WIRE 16 -1 (-800 25)(-800 75);
WIRE 16 -1 (-800 75)(-1100 75);
WIRE 16 -1 (-1100 25)(-1100 75);
WIRE 16 -1 (-1100 75)(-1375 75);
WIRE 16 -1 (-1375 25)(-1375 75);
WIRE 16 -1 (-1650 75)(-1375 75);
WIRE 16 -1 (-1650 25)(-1650 75);
WIRE 16 -1 (-1950 75)(-1650 75);
WIRE 16 -1 (-1950 25)(-1950 75);
WIRE 16 -1 (-2250 75)(-1950 75);
WIRE 16 -1 (-2250 25)(-2250 75);
WIRE 16 -1 (-2250 75)(-2250 125);
WIRE 16 -1 (2125 -175)(2125 -250);
WIRE 16 -1 (2125 -250)(1850 -250);
WIRE 16 -1 (1850 -175)(1850 -250);
WIRE 16 -1 (1850 -250)(1550 -250);
WIRE 16 -1 (1550 -175)(1550 -250);
WIRE 16 -1 (1550 -250)(1250 -250);
WIRE 16 -1 (1250 -175)(1250 -250);
WIRE 16 -1 (1250 -250)(975 -250);
WIRE 16 -1 (975 -175)(975 -250);
WIRE 16 -1 (975 -250)(700 -250);
WIRE 16 -1 (700 -175)(700 -250);
WIRE 16 -1 (700 -250)(400 -250);
WIRE 16 -1 (400 -175)(400 -250);
WIRE 16 -1 (400 -250)(100 -250);
WIRE 16 -1 (100 -175)(100 -250);
WIRE 16 -1 (100 -250)(-225 -250);
WIRE 16 -1 (-225 -175)(-225 -250);
WIRE 16 -1 (-225 -250)(-500 -250);
WIRE 16 -1 (-500 -175)(-500 -250);
WIRE 16 -1 (-500 -250)(-800 -250);
WIRE 16 -1 (-800 -175)(-800 -250);
WIRE 16 -1 (-800 -250)(-1100 -250);
WIRE 16 -1 (-1100 -175)(-1100 -250);
WIRE 16 -1 (-1100 -250)(-1375 -250);
WIRE 16 -1 (-1375 -175)(-1375 -250);
WIRE 16 -1 (-1650 -250)(-1375 -250);
WIRE 16 -1 (-1650 -175)(-1650 -250);
WIRE 16 -1 (-1650 -250)(-1950 -250);
WIRE 16 -1 (-1950 -175)(-1950 -250);
WIRE 16 -1 (-1950 -250)(-2250 -250);
WIRE 16 -1 (-2250 -175)(-2250 -250);
WIRE 16 -1 (-2250 -250)(-2250 -300);
WIRE 16 -1 (2150 -675)(2150 -625);
WIRE 16 -1 (2150 -625)(1875 -625);
WIRE 16 -1 (1875 -675)(1875 -625);
WIRE 16 -1 (1875 -625)(1575 -625);
WIRE 16 -1 (1575 -675)(1575 -625);
WIRE 16 -1 (1575 -625)(1275 -625);
WIRE 16 -1 (1275 -675)(1275 -625);
WIRE 16 -1 (1275 -625)(1000 -625);
WIRE 16 -1 (1000 -675)(1000 -625);
WIRE 16 -1 (1000 -625)(725 -625);
WIRE 16 -1 (725 -675)(725 -625);
WIRE 16 -1 (725 -625)(425 -625);
WIRE 16 -1 (425 -675)(425 -625);
WIRE 16 -1 (425 -625)(125 -625);
WIRE 16 -1 (125 -675)(125 -625);
WIRE 16 -1 (125 -625)(-200 -625);
WIRE 16 -1 (-200 -675)(-200 -625);
WIRE 16 -1 (-200 -625)(-475 -625);
WIRE 16 -1 (-475 -675)(-475 -625);
WIRE 16 -1 (-475 -625)(-775 -625);
WIRE 16 -1 (-775 -675)(-775 -625);
WIRE 16 -1 (-775 -625)(-1075 -625);
WIRE 16 -1 (-1075 -675)(-1075 -625);
WIRE 16 -1 (-1075 -625)(-1350 -625);
WIRE 16 -1 (-1350 -675)(-1350 -625);
WIRE 16 -1 (-1625 -625)(-1350 -625);
WIRE 16 -1 (-1625 -675)(-1625 -625);
WIRE 16 -1 (-1925 -625)(-1625 -625);
WIRE 16 -1 (-1925 -675)(-1925 -625);
WIRE 16 -1 (-2225 -625)(-1925 -625);
WIRE 16 -1 (-2225 -675)(-2225 -625);
WIRE 16 -1 (-2225 -625)(-2225 -575);
WIRE 16 -1 (2150 -875)(2150 -950);
WIRE 16 -1 (2150 -950)(1875 -950);
WIRE 16 -1 (1875 -875)(1875 -950);
WIRE 16 -1 (1875 -950)(1575 -950);
WIRE 16 -1 (1575 -875)(1575 -950);
WIRE 16 -1 (1575 -950)(1275 -950);
WIRE 16 -1 (1275 -875)(1275 -950);
WIRE 16 -1 (1275 -950)(1000 -950);
WIRE 16 -1 (1000 -875)(1000 -950);
WIRE 16 -1 (1000 -950)(725 -950);
WIRE 16 -1 (725 -875)(725 -950);
WIRE 16 -1 (725 -950)(425 -950);
WIRE 16 -1 (425 -875)(425 -950);
WIRE 16 -1 (425 -950)(125 -950);
WIRE 16 -1 (125 -875)(125 -950);
WIRE 16 -1 (125 -950)(-200 -950);
WIRE 16 -1 (-200 -875)(-200 -950);
WIRE 16 -1 (-200 -950)(-475 -950);
WIRE 16 -1 (-475 -875)(-475 -950);
WIRE 16 -1 (-475 -950)(-775 -950);
WIRE 16 -1 (-775 -875)(-775 -950);
WIRE 16 -1 (-775 -950)(-1075 -950);
WIRE 16 -1 (-1075 -875)(-1075 -950);
WIRE 16 -1 (-1075 -950)(-1350 -950);
WIRE 16 -1 (-1350 -875)(-1350 -950);
WIRE 16 -1 (-1625 -950)(-1350 -950);
WIRE 16 -1 (-1625 -875)(-1625 -950);
WIRE 16 -1 (-1625 -950)(-1925 -950);
WIRE 16 -1 (-1925 -875)(-1925 -950);
WIRE 16 -1 (-1925 -950)(-2225 -950);
WIRE 16 -1 (-2225 -875)(-2225 -950);
WIRE 16 -1 (-2225 -950)(-2225 -1000);
WIRE 16 -1 (275 1550)(275 1725);
WIRE 16 -1 (275 1725)(225 1725);
WIRE 16 -1 (300 2325)(300 2175);
WIRE 16 -1 (300 2175)(225 2175);
WIRE 16 -1 (4525 -400)(4525 -300);
WIRE 16 -1 (4150 -300)(4525 -300);
WIRE 16 -1 (4150 -400)(4150 -300);
WIRE 16 -1 (3750 -300)(4150 -300);
WIRE 16 -1 (3750 -375)(3750 -300);
WIRE 16 -1 (3325 -300)(3750 -300);
WIRE 16 -1 (3325 -375)(3325 -300);
WIRE 16 -1 (2900 -300)(3325 -300);
WIRE 16 -1 (2900 -375)(2900 -300);
WIRE 16 -1 (2900 -300)(2900 -225);
WIRE 16 -1 (4525 -600)(4525 -725);
WIRE 16 -1 (4150 -725)(4525 -725);
WIRE 16 -1 (4150 -600)(4150 -725);
WIRE 16 -1 (4150 -725)(3750 -725);
WIRE 16 -1 (3750 -575)(3750 -725);
WIRE 16 -1 (3750 -725)(3325 -725);
WIRE 16 -1 (3325 -575)(3325 -725);
WIRE 16 -1 (3325 -725)(2900 -725);
WIRE 16 -1 (2900 -725)(2900 -575);
WIRE 16 -1 (2900 -725)(2900 -850);
WIRE 16 -1 (5000 2925)(5000 3000);
WIRE 16 -1 (5000 3000)(4600 3000);
WIRE 16 -1 (4600 2925)(4600 3000);
WIRE 16 -1 (4600 3000)(4250 3000);
WIRE 16 -1 (4250 2925)(4250 3000);
WIRE 16 -1 (4250 3000)(3850 3000);
WIRE 16 -1 (3850 2925)(3850 3000);
WIRE 16 -1 (3850 3000)(3500 3000);
WIRE 16 -1 (3500 2925)(3500 3000);
WIRE 16 -1 (3500 3000)(3150 3000);
WIRE 16 -1 (3150 2925)(3150 3000);
WIRE 16 -1 (3150 3000)(2750 3000);
WIRE 16 -1 (2750 2925)(2750 3000);
WIRE 16 -1 (2400 3000)(2750 3000);
WIRE 16 -1 (2400 3000)(2400 2925);
WIRE 16 -1 (2400 3000)(2400 3050);
WIRE 16 -1 (2400 2725)(2400 2575);
WIRE 16 -1 (2400 2575)(2750 2575);
WIRE 16 -1 (2750 2725)(2750 2575);
WIRE 16 -1 (2750 2575)(3150 2575);
WIRE 16 -1 (3150 2725)(3150 2575);
WIRE 16 -1 (3150 2575)(3500 2575);
WIRE 16 -1 (3500 2725)(3500 2575);
WIRE 16 -1 (3500 2575)(3850 2575);
WIRE 16 -1 (3850 2725)(3850 2575);
WIRE 16 -1 (4125 2575)(3850 2575);
WIRE 16 -1 (4125 2575)(4250 2575);
WIRE 16 -1 (4125 2500)(4125 2575);
WIRE 16 -1 (4250 2575)(4600 2575);
WIRE 16 -1 (4250 2725)(4250 2575);
WIRE 16 -1 (4600 2575)(5000 2575);
WIRE 16 -1 (4600 2725)(4600 2575);
WIRE 16 -1 (5000 2725)(5000 2575);
WIRE 16 2175 (2225 3325)(5425 3325);
WIRE 16 2175 (2225 125)(2225 3325);
WIRE 16 2175 (5425 3325)(5425 125);
WIRE 16 2175 (5425 125)(2225 125);
WIRE 16 682 (-175 3375)(-175 2400);
WIRE 16 682 (-175 3375)(-2425 3375);
WIRE 16 682 (-175 2400)(-2425 2400);
WIRE 16 682 (-2425 2400)(-2425 3375);
WIRE 16 682 (5225 -1050)(5225 -75);
WIRE 16 682 (2700 -1050)(5225 -1050);
WIRE 16 682 (5225 -75)(2700 -75);
WIRE 16 682 (2700 -75)(2700 -1050);
WIRE 16 2175 (2300 2150)(5375 2150);
WIRE 16 -1 (-75 2175)(-375 2175);
WIRE 16 -1 (-375 2175)(-475 2175);
WIRE 16 -1 (-375 2025)(-375 2175);
WIRE 16 -1 (-475 2175)(-475 2025);
WIRE 16 -1 (-475 2025)(-875 2025);
WIRE 16 -1 (-875 2025)(-875 2150);
WIRE 16 -1 (-875 2150)(-1600 2150);
FORCEPROP 2 LAST SIG_NAME VSENSE_PVDDQ_KLM_P
J 0
(-1605 2165);
DISPLAY 0.617021 (-1605 2165);
PAINT ORANGE (-1605 2165);
WIRE 16 -1 (-375 1825)(-375 1725);
WIRE 16 -1 (-75 1725)(-375 1725);
WIRE 16 -1 (-375 1725)(-475 1725);
WIRE 16 -1 (-475 1950)(-475 1725);
WIRE 16 -1 (-875 1950)(-475 1950);
WIRE 16 -1 (-875 1800)(-875 1950);
WIRE 16 -1 (-1575 1800)(-875 1800);
FORCEPROP 2 LAST SIG_NAME VSENSE_PVDDQ_KLM_N
J 0
(-1585 1810);
DISPLAY 0.617021 (-1585 1810);
PAINT ORANGE (-1585 1810);
DOT 1 (-2225 -625);
DOT 1 (-2250 -250);
DOT 1 (-1925 -950);
DOT 1 (-1925 -625);
DOT 1 (-1625 -950);
DOT 1 (-1625 -625);
DOT 1 (-1350 -950);
DOT 1 (-1350 -625);
DOT 1 (-1075 -950);
DOT 1 (-1375 -250);
DOT 1 (-1100 -250);
DOT 1 (-775 -950);
DOT 1 (-775 -625);
DOT 1 (-800 -250);
DOT 1 (-500 -250);
DOT 1 (-475 -950);
DOT 1 (-475 -625);
DOT 1 (-200 -950);
DOT 1 (-200 -625);
DOT 1 (-225 -250);
DOT 1 (-2250 75);
DOT 1 (-2300 3075);
DOT 1 (-1950 75);
DOT 1 (-1650 75);
DOT 1 (-1100 75);
DOT 1 (-800 75);
DOT 1 (-500 75);
DOT 1 (-225 75);
DOT 1 (-675 1100);
DOT 1 (-375 1725);
DOT 1 (-1900 2650);
DOT 1 (-1200 2650);
DOT 1 (-1200 3075);
DOT 1 (-850 2650);
DOT 1 (-500 2650);
DOT 1 (-375 2175);
DOT 1 (-850 3075);
DOT 1 (125 -950);
DOT 1 (125 -625);
DOT 1 (425 -950);
DOT 1 (425 -625);
DOT 1 (100 -250);
DOT 1 (400 -250);
DOT 1 (725 -950);
DOT 1 (1000 -950);
DOT 1 (1000 -625);
DOT 1 (700 -250);
DOT 1 (975 -250);
DOT 1 (1275 -950);
DOT 1 (1275 -625);
DOT 1 (1250 -250);
DOT 1 (1575 -950);
DOT 1 (1575 -625);
DOT 1 (1875 -950);
DOT 1 (1875 -625);
DOT 1 (1550 -250);
DOT 1 (1850 -250);
DOT 1 (2900 -725);
DOT 1 (2900 -300);
DOT 1 (3325 -725);
DOT 1 (3325 -300);
DOT 1 (3750 -725);
DOT 1 (3750 -300);
DOT 1 (4150 -725);
DOT 1 (4150 -300);
DOT 1 (100 75);
DOT 1 (400 75);
DOT 1 (700 75);
DOT 1 (975 75);
DOT 1 (1250 75);
DOT 1 (1550 75);
DOT 1 (1850 75);
DOT 1 (2550 900);
DOT 1 (2900 475);
DOT 1 (2900 900);
DOT 1 (2525 1600);
DOT 1 (2875 1175);
DOT 1 (2875 1600);
DOT 1 (3300 475);
DOT 1 (3275 1175);
DOT 1 (3275 1600);
DOT 1 (3625 1175);
DOT 1 (3975 1175);
DOT 1 (3625 1600);
DOT 1 (3975 1600);
DOT 1 (2400 3000);
DOT 1 (2750 2575);
DOT 1 (2750 3000);
DOT 1 (3150 2575);
DOT 1 (3150 3000);
DOT 1 (3500 2575);
DOT 1 (3500 3000);
DOT 1 (3850 3000);
DOT 1 (3850 2575);
DOT 1 (4250 1175);
DOT 1 (4125 2575);
DOT 1 (4250 2575);
DOT 1 (4250 3000);
DOT 1 (4600 2575);
DOT 1 (4600 3000);
DOT 1 (-1375 75);
DOT 1 (-1650 -250);
DOT 1 (725 -625);
DOT 1 (-2225 -950);
DOT 1 (-1075 -625);
DOT 1 (-1950 -250);
DOT 1 (-1550 3075);
FORCENOTE
PVDDQ_KLM VOLTAGE SENSE
(-1570 1630) 0;
DISPLAY LEFT (-1570 1630);
PAINT PURPLE (-1570 1630);
FORCENOTE
INPUT FILTER
(-1405 805) 0;
DISPLAY LEFT (-1405 805);
PAINT PURPLE (-1405 805);
FORCENOTE
5MIL SPACING
(-845 1830) 0;
DISPLAY LEFT (-845 1830);
DISPLAY 0.808511 (-845 1830);
PAINT PURPLE (-845 1830);
FORCENOTE
ROUTE AS DIFF PAIR
(-895 1980) 0;
DISPLAY LEFT (-895 1980);
DISPLAY 0.808511 (-895 1980);
PAINT PURPLE (-895 1980);
FORCENOTE
10MIL WIDTH
(-820 1880) 0;
DISPLAY LEFT (-820 1880);
DISPLAY 0.808511 (-820 1880);
PAINT PURPLE (-820 1880);
FORCENOTE
TOP SIDE: 603
(-1198 3117) 0;
DISPLAY LEFT (-1198 3117);
DISPLAY 0.638298 (-1198 3117);
PAINT PURPLE (-1198 3117);
FORCENOTE
PVDDQ CPU CAVITY CAPS
(-1375 2425) 0;
DISPLAY LEFT (-1375 2425);
DISPLAY 1.021277 (-1375 2425);
PAINT PURPLE (-1375 2425);
FORCENOTE
CAD NOTE:
(3100 -900) 0;
DISPLAY LEFT (3100 -900);
DISPLAY 1.021277 (3100 -900);
PAINT PURPLE (3100 -900);
FORCENOTE
PLACE NEAR VR OUTPUT INDUCTORS
(3125 -975) 0;
DISPLAY LEFT (3125 -975);
DISPLAY 1.021277 (3125 -975);
PAINT PURPLE (3125 -975);
FORCENOTE
CAPS TO BE PLACED BETWEEN DIMMS
(2295 3255) 0;
DISPLAY LEFT (2295 3255);
DISPLAY 1.021277 (2295 3255);
PAINT PURPLE (2295 3255);
FORCENOTE
ROOM = VDDQ_KLM_PWR_VR
(-2390 -1285) 0;
DISPLAY LEFT (-2390 -1285);
DISPLAY 2.446809 (-2390 -1285);
PAINT PURPLE (-2390 -1285);
FORCENOTE
ROOM=VDDQ_KLM_CPU1
(-2375 2425) 0;
DISPLAY LEFT (-2375 2425);
DISPLAY 1.021277 (-2375 2425);
PAINT PURPLE (-2375 2425);
FORCENOTE
BOTTOM SIDE: 805
(-2229 3117) 0;
DISPLAY LEFT (-2229 3117);
DISPLAY 0.638298 (-2229 3117);
PAINT PURPLE (-2229 3117);
QUIT
